G04 ================== begin FILE IDENTIFICATION RECORD ==================*
G04 Layout Name:  9048_F0T_Management_Board_D_brd_V04_1213_1625.brd*
G04 Film Name:    pmt*
G04 File Format:  Gerber RS274X*
G04 File Origin:  Cadence Allegro 17.2-S081*
G04 Origin Date:  Tue Dec 13 16:31:10 2022*
G04 *
G04 Layer:  DRAWING FORMAT/TITLE_BLOCK_A*
G04 Layer:  VIA CLASS/PASTEMASK_TOP*
G04 Layer:  PIN/PASTEMASK_TOP*
G04 Layer:  PACKAGE GEOMETRY/PASTEMASK_TOP*
G04 Layer:  MANUFACTURING/PHOTOPLOT_OUTLINE*
G04 Layer:  DRAWING FORMAT/TITLE_BLOCK*
G04 Layer:  DRAWING FORMAT/TITLE_DATA_PMT*
G04 *
G04 Offset:    (0.00 0.00)*
G04 Mirror:    No*
G04 Mode:      Positive*
G04 Rotation:  0*
G04 FullContactRelief:  No*
G04 UndefLineWidth:     6.00*
G04 ================== end FILE IDENTIFICATION RECORD ====================*
%FSLAX25Y25*MOIN*%
%IR0*IPPOS*OFA0.00000B0.00000*MIA0B0*SFA1.00000B1.00000*%
%AMMACRO26*
4,1,32,-.01575,.06201,
-.01575,.0502,
.00197,.0502,
.00197,.04035,
-.01575,.04035,
-.01575,.03248,
.00197,.03248,
.00197,.02461,
-.01575,.02461,
-.01575,.01673,
.00197,.01673,
.00197,.00886,
-.01575,.00886,
-.01575,.00098,
.00197,.00098,
.00197,-.00689,
-.01575,-.00689,
-.01575,-.01476,
.00197,-.01476,
.00197,-.02264,
-.01575,-.02264,
-.01575,-.03051,
.00197,-.03051,
.00197,-.03839,
-.01575,-.03839,
-.01575,-.04626,
.00197,-.04626,
.00197,-.05413,
-.01575,-.05413,
-.01575,-.06201,
.01575,-.06201,
.01575,.06201,
-.01575,.06201,
0.0*
%
%ADD26MACRO26*%
%ADD104R,.231X.035*%
%ADD47R,.109X.04*%
%ADD57R,.049X.11*%
%ADD30R,.032X.007*%
%ADD10C,.03*%
%ADD113R,.105X.069*%
%ADD58C,.016*%
%ADD43C,.061*%
%ADD89R,.069X.105*%
%ADD87C,.044*%
%ADD41C,.026*%
%ADD110C,.0145*%
%ADD39R,.13X.0848*%
%ADD96R,.032X.032*%
%ADD60C,.048*%
%ADD14C,.039*%
%ADD44R,.061X.061*%
%ADD90R,.044X.044*%
%ADD54R,.048X.048*%
%AMMACRO17*
4,1,28,-.00748,-.00052,
-.00984,-.00052,
-.00984,-.00603,
-.009782,-.006705,
-.009607,-.007359,
-.009321,-.007974,
-.008933,-.008529,
-.008455,-.009009,
-.0079,-.009398,
-.007286,-.009685,
-.006632,-.009861,
-.005957,-.00992,
-.00591,-.00992,
.00591,-.00992,
.006585,-.009869,
.007242,-.009701,
.007859,-.009421,
.008418,-.009039,
.008903,-.008565,
.009297,-.008015,
.009591,-.007404,
.009773,-.006751,
.00984,-.006077,
.00984,-.00603,
.00984,-.00052,
.00748,-.00052,
.00748,.00991,
-.00748,.00991,
-.00748,-.00052,
0.0*
%
%ADD17MACRO17*%
%AMMACRO52*
4,1,5,.00098,-.01378,
-.00492,-.01378,
-.00492,.01378,
.00492,.01378,
.00492,-.00984,
.00098,-.01378,
0.0*
%
%ADD52MACRO52*%
%AMMACRO35*
4,1,5,.01378,.00098,
.01378,-.00492,
-.01378,-.00492,
-.01378,.00492,
.00984,.00492,
.01378,.00098,
0.0*
%
%ADD35MACRO35*%
%AMMACRO18*
4,1,28,-.00052,.00748,
-.00052,.00984,
-.00603,.00984,
-.006705,.009782,
-.007359,.009607,
-.007974,.009321,
-.008529,.008933,
-.009009,.008455,
-.009398,.0079,
-.009685,.007286,
-.009861,.006632,
-.00992,.005957,
-.00992,.00591,
-.00992,-.00591,
-.009869,-.006585,
-.009701,-.007242,
-.009421,-.007859,
-.009039,-.008418,
-.008565,-.008903,
-.008015,-.009297,
-.007404,-.009591,
-.006751,-.009773,
-.006077,-.00984,
-.00603,-.00984,
-.00052,-.00984,
-.00052,-.00748,
.00991,-.00748,
.00991,.00748,
-.00052,.00748,
0.0*
%
%ADD18MACRO18*%
%ADD11R,.079X.079*%
%AMMACRO16*
4,1,28,-.00748,.00051,
-.00984,.00051,
-.00984,.00602,
-.009782,.006695,
-.009607,.007349,
-.009321,.007964,
-.008933,.008519,
-.008455,.008998,
-.0079,.009388,
-.007287,.009675,
-.006632,.009851,
-.005958,.00991,
-.00591,.00991,
.00591,.00991,
.006585,.009859,
.007242,.009691,
.007859,.009411,
.008418,.009029,
.008903,.008555,
.009297,.008005,
.00959,.007394,
.009773,.006742,
.00984,.006068,
.00984,.00602,
.00984,.00051,
.00748,.00051,
.00748,-.00992,
-.00748,-.00992,
-.00748,.00051,
0.0*
%
%ADD16MACRO16*%
%AMMACRO40*
4,1,5,-.00098,-.01378,
.00492,-.01378,
.00492,.01378,
-.00492,.01378,
-.00492,-.00984,
-.00098,-.01378,
0.0*
%
%ADD40MACRO40*%
%AMMACRO34*
4,1,5,.01378,-.00098,
.01378,.00492,
-.01378,.00492,
-.01378,-.00492,
.00984,-.00492,
.01378,-.00098,
0.0*
%
%ADD34MACRO34*%
%AMMACRO25*
4,1,28,.00051,.00748,
.00051,.00984,
.00602,.00984,
.006695,.009782,
.007349,.009607,
.007964,.009321,
.008519,.008933,
.008998,.008455,
.009388,.0079,
.009675,.007287,
.009851,.006632,
.00991,.005958,
.00991,.00591,
.00991,-.00591,
.009859,-.006585,
.009691,-.007242,
.009411,-.007859,
.009029,-.008418,
.008555,-.008903,
.008005,-.009297,
.007394,-.00959,
.006742,-.009773,
.006068,-.00984,
.00602,-.00984,
.00051,-.00984,
.00051,-.00748,
-.00992,-.00748,
-.00992,.00748,
.00051,.00748,
0.0*
%
%ADD25MACRO25*%
%ADD24R,.13X.13*%
%AMMACRO29*
4,1,5,.01772,.00591,
-.01772,.00591,
-.01772,0.0,
-.01181,-.00591,
.01772,-.00591,
.01772,.00591,
0.0*
%
%ADD29MACRO29*%
%ADD105R,.06X.02*%
%ADD78R,.025X.01*%
%ADD27R,.032X.012*%
%ADD99R,.034X.02*%
%ADD93R,.01X.025*%
%ADD83R,.022X.04*%
%ADD75R,.02X.024*%
%ADD59R,.02X.016*%
%ADD37R,.01X.052*%
%ADD108R,.024X.022*%
%ADD107R,.022X.032*%
%ADD74R,.02X.017*%
%ADD45R,.015X.04*%
%ADD31R,.04X.05*%
%ADD106R,.04X.015*%
%ADD84R,.036X.011*%
%ADD63R,.028X.01*%
%ADD46R,.017X.02*%
%ADD36R,.01X.036*%
%ADD112R,.011X.036*%
%ADD68R,.011X.063*%
%ADD61R,.01X.028*%
%ADD53R,.018X.02*%
%ADD81R,.061X.024*%
%ADD66R,.011X.028*%
%ADD65R,.014X.034*%
%ADD101R,.046X.013*%
%ADD100R,.034X.016*%
%ADD80C,.131*%
%ADD77R,.023X.018*%
%ADD71R,.036X.014*%
%ADD70R,.04X.028*%
%ADD56R,.014X.044*%
%ADD42R,.024X.017*%
%ADD94R,.014X.036*%
%ADD91R,.018X.023*%
%ADD79R,.017X.024*%
%ADD73R,.036X.024*%
%ADD69R,.056X.04*%
%ADD55R,.013X.046*%
%ADD48R,.028X.04*%
%ADD32R,.032X.028*%
%ADD95R,.052X.018*%
%ADD67R,.028X.032*%
%ADD62R,.01X.059*%
%ADD109R,.024X.028*%
%ADD102R,.046X.034*%
%ADD98R,.038X.024*%
%ADD86R,.02X.059*%
%ADD72R,.054X.026*%
%ADD15R,.054X.044*%
%ADD111R,.049X.014*%
%ADD82R,.027X.018*%
%ADD64R,.044X.054*%
%ADD97R,.046X.062*%
%ADD92R,.018X.027*%
%ADD88R,.071X.048*%
%ADD76R,.018X.028*%
%ADD28R,.012X.079*%
%ADD103C,.237*%
%ADD85R,.017X.067*%
%ADD13C,.238*%
%ADD12C,.256*%
%ADD22R,.046X.069*%
%AMMACRO33*
4,1,28,.00052,-.00748,
.00052,-.00984,
.00603,-.00984,
.006705,-.009782,
.007359,-.009607,
.007974,-.009321,
.008529,-.008933,
.009009,-.008455,
.009398,-.0079,
.009685,-.007286,
.009861,-.006632,
.00992,-.005957,
.00992,-.00591,
.00992,.00591,
.009869,.006585,
.009701,.007242,
.009421,.007859,
.009039,.008418,
.008565,.008903,
.008015,.009297,
.007404,.009591,
.006751,.009773,
.006077,.00984,
.00603,.00984,
.00052,.00984,
.00052,.00748,
-.00991,.00748,
-.00991,-.00748,
.00052,-.00748,
0.0*
%
%ADD33MACRO33*%
%AMMACRO21*
4,1,28,.00748,.00052,
.00984,.00052,
.00984,.00603,
.009782,.006705,
.009607,.007359,
.009321,.007974,
.008933,.008529,
.008455,.009009,
.0079,.009398,
.007286,.009685,
.006632,.009861,
.005957,.00992,
.00591,.00992,
-.00591,.00992,
-.006585,.009869,
-.007242,.009701,
-.007859,.009421,
-.008418,.009039,
-.008903,.008565,
-.009297,.008015,
-.009591,.007404,
-.009773,.006751,
-.00984,.006077,
-.00984,.00603,
-.00984,.00052,
-.00748,.00052,
-.00748,-.00991,
.00748,-.00991,
.00748,.00052,
0.0*
%
%ADD21MACRO21*%
%ADD23R,.059X.079*%
%AMMACRO50*
4,1,5,-.01378,-.00098,
-.01378,.00492,
.01378,.00492,
.01378,-.00492,
-.00984,-.00492,
-.01378,-.00098,
0.0*
%
%ADD50MACRO50*%
%AMMACRO20*
4,1,28,-.00051,-.00748,
-.00051,-.00984,
-.00602,-.00984,
-.006695,-.009782,
-.007349,-.009607,
-.007964,-.009321,
-.008519,-.008933,
-.008998,-.008455,
-.009388,-.0079,
-.009675,-.007287,
-.009851,-.006632,
-.00991,-.005958,
-.00991,-.00591,
-.00991,.00591,
-.009859,.006585,
-.009691,.007242,
-.009411,.007859,
-.009029,.008418,
-.008555,.008903,
-.008005,.009297,
-.007394,.00959,
-.006742,.009773,
-.006068,.00984,
-.00602,.00984,
-.00051,.00984,
-.00051,.00748,
.00992,.00748,
.00992,-.00748,
-.00051,-.00748,
0.0*
%
%ADD20MACRO20*%
%AMMACRO19*
4,1,28,.00748,-.00051,
.00984,-.00051,
.00984,-.00602,
.009782,-.006695,
.009607,-.007349,
.009321,-.007964,
.008933,-.008519,
.008455,-.008998,
.0079,-.009388,
.007287,-.009675,
.006632,-.009851,
.005958,-.00991,
.00591,-.00991,
-.00591,-.00991,
-.006585,-.009859,
-.007242,-.009691,
-.007859,-.009411,
-.008418,-.009029,
-.008903,-.008555,
-.009297,-.008005,
-.00959,-.007394,
-.009773,-.006742,
-.00984,-.006068,
-.00984,-.00602,
-.00984,-.00051,
-.00748,-.00051,
-.00748,.00992,
.00748,.00992,
.00748,-.00051,
0.0*
%
%ADD19MACRO19*%
%AMMACRO38*
4,1,5,-.00098,.01378,
.00492,.01378,
.00492,-.01378,
-.00492,-.01378,
-.00492,.00984,
-.00098,.01378,
0.0*
%
%ADD38MACRO38*%
%AMMACRO49*
4,1,5,-.01378,.00098,
-.01378,-.00492,
.01378,-.00492,
.01378,.00492,
-.00984,.00492,
-.01378,.00098,
0.0*
%
%ADD49MACRO49*%
%AMMACRO51*
4,1,5,.00098,.01378,
-.00492,.01378,
-.00492,-.01378,
.00492,-.01378,
.00492,.00984,
.00098,.01378,
0.0*
%
%ADD51MACRO51*%
%ADD114C,.006*%
G75*
%LPD*%
G75*
G54D100*
X197012Y299320D03*
Y301880D03*
X210988D03*
Y299320D03*
G54D101*
X203211Y316159D03*
Y311041D03*
X210789Y316159D03*
Y313600D03*
Y311041D03*
G54D110*
X293907Y164990D03*
X290757D03*
X287608D03*
X293907Y168140D03*
X290757D03*
X287608D03*
X293907Y171289D03*
X290757D03*
X287608D03*
X293907Y174439D03*
X290757D03*
X287608D03*
X293907Y177588D03*
X290757D03*
X287608D03*
X293907Y180738D03*
X290757D03*
X287608D03*
X293907Y183888D03*
X290757D03*
X287608D03*
X293907Y187037D03*
X290757D03*
X287608D03*
X293907Y190187D03*
X290757D03*
X287608D03*
X293907Y193336D03*
X290757D03*
X287608D03*
X293907Y196486D03*
X290757D03*
X287608D03*
X293907Y199636D03*
X290757D03*
X287608D03*
X293907Y202785D03*
X290757D03*
X287608D03*
X293907Y205935D03*
X290757D03*
X287608D03*
X293907Y209084D03*
X290757D03*
X287608D03*
X293907Y212234D03*
X290757D03*
X287608D03*
X312804Y164990D03*
X309655D03*
X306505D03*
X312804Y168140D03*
X309655D03*
X306505D03*
X312804Y171289D03*
X309655D03*
X306505D03*
X312804Y174439D03*
X309655D03*
X306505D03*
X312804Y177588D03*
X309655D03*
X306505D03*
X312804Y180738D03*
X309655D03*
X306505D03*
X312804Y183888D03*
X309655D03*
X306505D03*
X312804Y187037D03*
X309655D03*
X306505D03*
X312804Y190187D03*
X309655D03*
X306505D03*
X312804Y193336D03*
X309655D03*
X306505D03*
X312804Y196486D03*
X309655D03*
X306505D03*
X312804Y199636D03*
X309655D03*
X306505D03*
X312804Y202785D03*
X309655D03*
X306505D03*
X312804Y205935D03*
X309655D03*
X306505D03*
X312804Y209084D03*
X309655D03*
X306505D03*
X312804Y212234D03*
X309655D03*
X306505D03*
G54D111*
X317580Y67941D03*
Y73059D03*
X325020D03*
Y70500D03*
Y67941D03*
G54D102*
X228832Y107236D03*
X220564D03*
Y113732D03*
X228832D03*
G54D103*
X236220Y424016D03*
X301181D03*
G54D112*
X329290Y126103D03*
X321416D03*
Y138309D03*
X329290D03*
X327322Y126103D03*
X325353D03*
X323384D03*
Y138309D03*
X325353D03*
X327322D03*
G54D10*
X-23737Y543288D03*
X-16737Y536288D03*
X-16500Y544500D03*
X6590Y264520D03*
X10000Y123500D03*
X7800Y194400D03*
X10800Y234200D03*
X15500Y252000D03*
X10500Y245400D03*
X25600Y106300D03*
X36292Y208592D03*
X50700Y439100D03*
X62321Y69200D03*
X62259Y211100D03*
X54975Y215900D03*
X62520Y233600D03*
X55240Y243700D03*
X58800Y265000D03*
X63945Y427055D03*
X71589Y118250D03*
X67400Y155600D03*
X76000Y175100D03*
X81000Y212330D03*
X70289Y227521D03*
X80200Y234100D03*
X67699Y235380D03*
X69187Y429000D03*
X94500Y127000D03*
X83950Y134950D03*
X86000Y147700D03*
X92200Y141540D03*
X85794Y227069D03*
X84941Y232100D03*
X89675Y421940D03*
X88565Y433040D03*
X105030Y96300D03*
X109800Y422300D03*
X103070Y432630D03*
X110200Y431600D03*
X124000Y50100D03*
X124801Y148130D03*
X123906Y188194D03*
X121200Y234890D03*
X119600Y261500D03*
X137540Y169500D03*
X129810Y191310D03*
X132398Y232400D03*
X132100Y346600D03*
X148314Y193687D03*
X155500Y200500D03*
X153000Y348600D03*
X164982Y164842D03*
X164472Y169902D03*
X164601Y181492D03*
X164426Y174982D03*
X165000Y191807D03*
X164879Y186543D03*
X164800Y198000D03*
X163500Y229184D03*
X167500Y312500D03*
X160500Y318500D03*
X166000Y305500D03*
X169600Y432670D03*
X166450Y424810D03*
X161120Y424590D03*
X181595Y142905D03*
X183500Y245500D03*
X181750Y337300D03*
X178300Y348600D03*
X179800Y423989D03*
X190912Y90313D03*
X191100Y96066D03*
X198703Y143302D03*
X186800Y142800D03*
X192194Y142712D03*
X190708Y245541D03*
X196170Y245552D03*
X188500Y274900D03*
X192500Y278000D03*
X192380Y291900D03*
X191199Y300200D03*
X191230Y305500D03*
X188546Y326356D03*
X200274Y410960D03*
X200048Y418652D03*
X195000Y422540D03*
X186720Y432490D03*
X212872Y48793D03*
X211400Y59238D03*
X200900Y110800D03*
X206200Y102200D03*
X214814Y142700D03*
X203703Y143307D03*
X202600Y245500D03*
X213000Y250500D03*
X206440Y261171D03*
X214034Y261482D03*
X205900Y266130D03*
X204207Y278200D03*
X213700Y363100D03*
X208300Y398150D03*
X202674Y404600D03*
X208830Y424500D03*
X229900Y61000D03*
X227547Y74275D03*
X215900Y73800D03*
X227760Y82524D03*
X217262Y129294D03*
X224784Y142600D03*
X219800Y143250D03*
X230400Y249600D03*
X220866Y272160D03*
X226405Y266335D03*
X229220Y283250D03*
X217400Y295200D03*
X217673Y300600D03*
X228300Y319400D03*
X218100Y305600D03*
X226075Y309390D03*
X228230Y340040D03*
X219800Y364200D03*
X224101Y352320D03*
X226428Y411600D03*
X233400Y123100D03*
X241900Y114300D03*
X233511Y129594D03*
Y142983D03*
X241100Y245510D03*
X244150Y250920D03*
X235326Y245472D03*
X235006Y263591D03*
X234500Y293500D03*
X237900Y324300D03*
X237500Y343000D03*
X235370Y403500D03*
X241231Y407285D03*
X257145Y279700D03*
X257900Y312100D03*
X249400Y410300D03*
X251800Y416600D03*
X257900Y416700D03*
X256400Y431500D03*
X250800Y432500D03*
X264989Y101732D03*
X271500Y111600D03*
X267204Y185566D03*
X274835Y189927D03*
X262100Y280700D03*
X268170Y359840D03*
X273580Y354250D03*
X272581Y376280D03*
X268200Y373400D03*
Y390100D03*
X274880Y387292D03*
X260300Y403370D03*
X270000Y431600D03*
X261400Y433100D03*
X280125Y55200D03*
X280293Y60430D03*
X289736Y78607D03*
X280270Y88470D03*
X284222Y103300D03*
X275528Y163811D03*
X281889Y287636D03*
X285911Y279569D03*
X286372Y320700D03*
X288200Y348300D03*
X276400Y370400D03*
X285500Y426100D03*
X278400Y426400D03*
X284200Y432900D03*
X293773Y73530D03*
X302091Y74553D03*
X291720Y95610D03*
X298575Y101900D03*
X303600Y132200D03*
X302001Y242900D03*
X298100Y283900D03*
X290120Y339370D03*
X290501Y377400D03*
X290450Y382690D03*
X315080Y95980D03*
X310768Y102012D03*
X307101Y249100D03*
X313763Y274756D03*
X312300Y340700D03*
X328000Y62100D03*
X322500Y102900D03*
X320779Y111030D03*
X327383Y164347D03*
X327830Y174403D03*
X324777Y182042D03*
X328265Y187045D03*
X328100Y293800D03*
X341000Y61300D03*
X345195Y105845D03*
X343600Y118900D03*
X337004Y202113D03*
Y210113D03*
G54D20*
X16916Y328600D03*
X33816Y214700D03*
X27181Y246113D03*
X27816Y264500D03*
X25216Y316900D03*
X37016Y38000D03*
X42500Y214718D03*
X43616Y241000D03*
X44416Y248800D03*
X36508Y246116D03*
X43616Y244900D03*
X48816Y260800D03*
X34816Y264500D03*
X47016Y328000D03*
Y324000D03*
Y344000D03*
Y348000D03*
Y364000D03*
Y368000D03*
Y372000D03*
Y376000D03*
Y380000D03*
Y384000D03*
X47416Y394350D03*
X50732Y38500D03*
X63491Y116450D03*
X51666Y211200D03*
X78082Y118216D03*
X74535Y135866D03*
X91506Y428020D03*
X108016Y102000D03*
Y107500D03*
X115116Y102000D03*
Y107600D03*
X114516Y123500D03*
X118816Y346400D03*
Y342500D03*
X116016Y415000D03*
X127516Y50000D03*
X134016Y201500D03*
X130516Y253700D03*
X129716Y261900D03*
X136916Y348300D03*
Y351900D03*
X133116Y429000D03*
X149516Y142000D03*
X140516Y175200D03*
X140526Y179160D03*
X148610Y182594D03*
X146596Y419250D03*
X150516Y429000D03*
X163316Y112800D03*
X156421Y153077D03*
X155625Y182644D03*
X155732Y178679D03*
X155716Y174800D03*
X155766Y187354D03*
X155816Y191700D03*
X156516Y224000D03*
X155315Y313560D03*
X155316Y309700D03*
X158016Y350500D03*
X183016Y88000D03*
Y92000D03*
X171416Y272800D03*
X187016Y267000D03*
X194016Y264810D03*
X184616Y294500D03*
X189216Y311100D03*
X207656Y244900D03*
X206816Y419600D03*
X214436Y102014D03*
X222136Y258930D03*
X223016Y296600D03*
Y300600D03*
X217916Y416000D03*
X233316Y319400D03*
X254316Y98600D03*
Y95100D03*
X252116Y110300D03*
X266977Y368610D03*
Y381075D03*
X281226Y93260D03*
X273736Y99350D03*
X283074Y138403D03*
X294516Y79500D03*
X289016Y100400D03*
X294776Y142907D03*
X297516Y311500D03*
X290241Y358508D03*
Y363008D03*
X289777Y387500D03*
X303016Y79500D03*
X305397Y273256D03*
X326143Y144423D03*
X321396Y275940D03*
X320175Y294816D03*
X334316Y70000D03*
X334341Y154911D03*
Y164911D03*
Y159911D03*
Y169911D03*
Y179911D03*
Y174911D03*
Y183926D03*
Y189911D03*
X333840Y292085D03*
G54D11*
X14961Y10591D03*
X48031D03*
X261418Y12166D03*
X294488D03*
X306300Y10591D03*
X339370D03*
G54D113*
X325353Y132206D03*
G54D104*
X246858Y355831D03*
Y391067D03*
X311819Y355831D03*
Y391067D03*
G54D114*
G01X2010999Y-388000D02*
Y1475775D01*
X-407000D01*
Y-386798D01*
Y-755294D01*
Y-793716D01*
X-368578D01*
X1942346D01*
X2010999D01*
Y-725063D01*
Y-388000D01*
G01X-53307Y-609436D02*
Y-684436D01*
X446693D01*
Y-609436D01*
X-53307D01*
G01X-41307Y-674436D02*
Y-679436D01*
G01X-42764Y-674436D02*
X-39850D01*
G01X-34940Y-679436D02*
X-37474D01*
Y-674436D01*
X-34940D01*
G01X-35954Y-676853D02*
X-37474D01*
G01X-32374Y-674436D02*
Y-679436D01*
X-29840D01*
G01X-26007Y-679603D02*
X-26134Y-679519D01*
Y-679353D01*
X-26007Y-679269D01*
X-25880Y-679353D01*
Y-679519D01*
X-26007Y-679603D01*
G01Y-677353D02*
X-26134Y-677269D01*
Y-677103D01*
X-26007Y-677019D01*
X-25880Y-677103D01*
Y-677269D01*
X-26007Y-677353D01*
G01X-21224Y-681103D02*
X-21857Y-680269D01*
X-22174Y-679436D01*
Y-676103D01*
X-21857Y-675269D01*
X-21224Y-674436D01*
G01X-15807D02*
X-16314Y-674603D01*
X-16694Y-675019D01*
X-16947Y-675519D01*
X-17137Y-676186D01*
X-17200Y-676936D01*
X-17137Y-677686D01*
X-16947Y-678353D01*
X-16694Y-678853D01*
X-16314Y-679269D01*
X-15807Y-679436D01*
X-15300Y-679269D01*
X-14920Y-678853D01*
X-14667Y-678353D01*
X-14477Y-677686D01*
X-14414Y-676936D01*
X-14477Y-676186D01*
X-14667Y-675519D01*
X-14920Y-675019D01*
X-15300Y-674603D01*
X-15807Y-674436D01*
G01X-12100Y-678436D02*
X-11720Y-679019D01*
X-11214Y-679353D01*
X-10644Y-679436D01*
X-10137Y-679353D01*
X-9630Y-678936D01*
X-9314Y-678436D01*
X-9250Y-677936D01*
X-9377Y-677353D01*
X-9820Y-676936D01*
X-10264Y-676769D01*
X-10834D01*
G01X-10264D02*
X-9884Y-676519D01*
X-9567Y-676103D01*
X-9440Y-675603D01*
X-9567Y-675103D01*
X-9884Y-674686D01*
X-10454Y-674436D01*
X-11024Y-674519D01*
X-11594Y-674853D01*
G01X-5290Y-681103D02*
X-4657Y-680269D01*
X-4340Y-679436D01*
Y-676103D01*
X-4657Y-675269D01*
X-5290Y-674436D01*
G01X-1900Y-678436D02*
X-1520Y-679019D01*
X-1014Y-679353D01*
X-444Y-679436D01*
X63Y-679353D01*
X570Y-678936D01*
X886Y-678436D01*
X950Y-677936D01*
X823Y-677353D01*
X380Y-676936D01*
X-64Y-676769D01*
X-634D01*
G01X-64D02*
X316Y-676519D01*
X633Y-676103D01*
X760Y-675603D01*
X633Y-675103D01*
X316Y-674686D01*
X-254Y-674436D01*
X-824Y-674519D01*
X-1394Y-674853D01*
G01X3390Y-675269D02*
X3770Y-674769D01*
X4213Y-674519D01*
X4720Y-674436D01*
X5353Y-674603D01*
X5796Y-675019D01*
X5923Y-675519D01*
X5860Y-676019D01*
X5606Y-676436D01*
X4340Y-677269D01*
X3770Y-677853D01*
X3390Y-678686D01*
X3263Y-679436D01*
X5923D01*
G01X9566D02*
X9693Y-678353D01*
X9883Y-677436D01*
X10136Y-676603D01*
X10453Y-675686D01*
X10960Y-674436D01*
X8426D01*
G01X13970Y-677769D02*
X15616D01*
G01X18690Y-675269D02*
X19070Y-674769D01*
X19513Y-674519D01*
X20020Y-674436D01*
X20653Y-674603D01*
X21096Y-675019D01*
X21223Y-675519D01*
X21160Y-676019D01*
X20906Y-676436D01*
X19640Y-677269D01*
X19070Y-677853D01*
X18690Y-678686D01*
X18563Y-679436D01*
X21223D01*
G01X23600Y-678436D02*
X23980Y-679019D01*
X24486Y-679353D01*
X25056Y-679436D01*
X25563Y-679353D01*
X26070Y-678936D01*
X26386Y-678436D01*
X26450Y-677936D01*
X26323Y-677353D01*
X25880Y-676936D01*
X25436Y-676769D01*
X24866D01*
G01X25436D02*
X25816Y-676519D01*
X26133Y-676103D01*
X26260Y-675603D01*
X26133Y-675103D01*
X25816Y-674686D01*
X25246Y-674436D01*
X24676Y-674519D01*
X24106Y-674853D01*
G01X30853Y-679436D02*
Y-674436D01*
X28510Y-678019D01*
X31676D01*
G01X33800Y-678686D02*
X34180Y-679103D01*
X34623Y-679353D01*
X35193Y-679436D01*
X35763Y-679269D01*
X36206Y-678936D01*
X36523Y-678353D01*
X36586Y-677686D01*
X36460Y-677019D01*
X36143Y-676603D01*
X35700Y-676269D01*
X35256Y-676186D01*
X34813Y-676269D01*
X34243Y-676603D01*
X34433Y-674436D01*
X36143D01*
G01X44190Y-679436D02*
Y-674436D01*
X46596D01*
G01X45710Y-676853D02*
X44190D01*
G01X48910Y-679436D02*
X50493Y-674436D01*
X52076Y-679436D01*
G01X51506Y-677686D02*
X49480D01*
G01X54263Y-679436D02*
X56923Y-674436D01*
G01X54263D02*
X56923Y-679436D01*
G01X60693Y-679603D02*
X60566Y-679519D01*
Y-679353D01*
X60693Y-679269D01*
X60820Y-679353D01*
Y-679519D01*
X60693Y-679603D01*
G01Y-677353D02*
X60566Y-677269D01*
Y-677103D01*
X60693Y-677019D01*
X60820Y-677103D01*
Y-677269D01*
X60693Y-677353D01*
G01X65476Y-681103D02*
X64843Y-680269D01*
X64526Y-679436D01*
Y-676103D01*
X64843Y-675269D01*
X65476Y-674436D01*
G01X70893D02*
X70386Y-674603D01*
X70006Y-675019D01*
X69753Y-675519D01*
X69563Y-676186D01*
X69500Y-676936D01*
X69563Y-677686D01*
X69753Y-678353D01*
X70006Y-678853D01*
X70386Y-679269D01*
X70893Y-679436D01*
X71400Y-679269D01*
X71780Y-678853D01*
X72033Y-678353D01*
X72223Y-677686D01*
X72286Y-676936D01*
X72223Y-676186D01*
X72033Y-675519D01*
X71780Y-675019D01*
X71400Y-674603D01*
X70893Y-674436D01*
G01X74600Y-678436D02*
X74980Y-679019D01*
X75486Y-679353D01*
X76056Y-679436D01*
X76563Y-679353D01*
X77070Y-678936D01*
X77386Y-678436D01*
X77450Y-677936D01*
X77323Y-677353D01*
X76880Y-676936D01*
X76436Y-676769D01*
X75866D01*
G01X76436D02*
X76816Y-676519D01*
X77133Y-676103D01*
X77260Y-675603D01*
X77133Y-675103D01*
X76816Y-674686D01*
X76246Y-674436D01*
X75676Y-674519D01*
X75106Y-674853D01*
G01X81410Y-681103D02*
X82043Y-680269D01*
X82360Y-679436D01*
Y-676103D01*
X82043Y-675269D01*
X81410Y-674436D01*
G01X84800Y-678436D02*
X85180Y-679019D01*
X85686Y-679353D01*
X86256Y-679436D01*
X86763Y-679353D01*
X87270Y-678936D01*
X87586Y-678436D01*
X87650Y-677936D01*
X87523Y-677353D01*
X87080Y-676936D01*
X86636Y-676769D01*
X86066D01*
G01X86636D02*
X87016Y-676519D01*
X87333Y-676103D01*
X87460Y-675603D01*
X87333Y-675103D01*
X87016Y-674686D01*
X86446Y-674436D01*
X85876Y-674519D01*
X85306Y-674853D01*
G01X90216Y-678853D02*
X90660Y-679269D01*
X91166Y-679436D01*
X91673Y-679269D01*
X92116Y-678769D01*
X92433Y-678019D01*
X92560Y-677269D01*
Y-676353D01*
X92433Y-675603D01*
X92116Y-674936D01*
X91736Y-674603D01*
X91293Y-674436D01*
X90786Y-674603D01*
X90406Y-674936D01*
X90153Y-675436D01*
X90026Y-676103D01*
X90153Y-676686D01*
X90470Y-677269D01*
X90850Y-677603D01*
X91293Y-677686D01*
X91800Y-677519D01*
X92180Y-677103D01*
X92560Y-676353D01*
G01X96266Y-679436D02*
X96393Y-678353D01*
X96583Y-677436D01*
X96836Y-676603D01*
X97153Y-675686D01*
X97660Y-674436D01*
X95126D01*
G01X100670Y-677769D02*
X102316D01*
G01X105200Y-678436D02*
X105580Y-679019D01*
X106086Y-679353D01*
X106656Y-679436D01*
X107163Y-679353D01*
X107670Y-678936D01*
X107986Y-678436D01*
X108050Y-677936D01*
X107923Y-677353D01*
X107480Y-676936D01*
X107036Y-676769D01*
X106466D01*
G01X107036D02*
X107416Y-676519D01*
X107733Y-676103D01*
X107860Y-675603D01*
X107733Y-675103D01*
X107416Y-674686D01*
X106846Y-674436D01*
X106276Y-674519D01*
X105706Y-674853D01*
G01X110490Y-677353D02*
X110933Y-676769D01*
X111313Y-676436D01*
X111820Y-676269D01*
X112263Y-676436D01*
X112580Y-676769D01*
X112833Y-677269D01*
X112896Y-677853D01*
X112833Y-678353D01*
X112580Y-678853D01*
X112200Y-679269D01*
X111756Y-679436D01*
X111250Y-679269D01*
X110806Y-678769D01*
X110553Y-678019D01*
X110490Y-677186D01*
X110616Y-676103D01*
X110806Y-675519D01*
X111123Y-674936D01*
X111566Y-674519D01*
X112010Y-674436D01*
X112453Y-674603D01*
X112770Y-675019D01*
G01X116793Y-679436D02*
Y-674436D01*
X116033Y-675436D01*
G01Y-679436D02*
X117553D01*
G01X122653D02*
Y-674436D01*
X120310Y-678019D01*
X123476D01*
G01X141693Y-609436D02*
Y-684436D01*
G01Y-659436D02*
X244693D01*
Y-634436D01*
G01X141693D02*
X244693D01*
G01X246693Y-609436D02*
Y-684436D01*
G01X244693Y-609436D02*
Y-684436D01*
G01X252200Y-669436D02*
Y-664436D01*
X253466D01*
X253973Y-664686D01*
X254353Y-665019D01*
X254670Y-665519D01*
X254923Y-666103D01*
X254986Y-666936D01*
X254923Y-667769D01*
X254670Y-668353D01*
X254353Y-668853D01*
X253973Y-669186D01*
X253466Y-669436D01*
X252200D01*
G01X257110D02*
X258693Y-664436D01*
X260276Y-669436D01*
G01X259706Y-667686D02*
X257680D01*
G01X263793Y-664436D02*
Y-669436D01*
G01X262336Y-664436D02*
X265250D01*
G01X270160Y-669436D02*
X267626D01*
Y-664436D01*
X270160D01*
G01X269146Y-666853D02*
X267626D01*
G01X273993Y-669603D02*
X273866Y-669519D01*
Y-669353D01*
X273993Y-669269D01*
X274120Y-669353D01*
Y-669519D01*
X273993Y-669603D01*
G01Y-667353D02*
X273866Y-667269D01*
Y-667103D01*
X273993Y-667019D01*
X274120Y-667103D01*
Y-667269D01*
X273993Y-667353D01*
G01X246693Y-659436D02*
X446693D01*
G01X252326Y-644436D02*
Y-639436D01*
X253846D01*
X254353Y-639686D01*
X254733Y-640269D01*
X254860Y-640936D01*
X254733Y-641603D01*
X254416Y-642103D01*
X253846Y-642353D01*
X252326D01*
G01X257553Y-644603D02*
X259833Y-639436D01*
G01X262336Y-644436D02*
Y-639436D01*
X265250Y-644436D01*
Y-639436D01*
G01X268893Y-644603D02*
X268766Y-644519D01*
Y-644353D01*
X268893Y-644269D01*
X269020Y-644353D01*
Y-644519D01*
X268893Y-644603D01*
G01Y-642353D02*
X268766Y-642269D01*
Y-642103D01*
X268893Y-642019D01*
X269020Y-642103D01*
Y-642269D01*
X268893Y-642353D01*
G01X246693Y-634436D02*
X446693D01*
G01X252326Y-619436D02*
Y-614436D01*
X253846D01*
X254353Y-614686D01*
X254733Y-615269D01*
X254860Y-615936D01*
X254733Y-616603D01*
X254416Y-617103D01*
X253846Y-617353D01*
X252326D01*
G01X257426Y-619436D02*
Y-614436D01*
X259010D01*
X259516Y-614686D01*
X259833Y-615019D01*
X259960Y-615686D01*
X259833Y-616353D01*
X259453Y-616769D01*
X259010Y-617019D01*
X257426D01*
G01X259010D02*
X259960Y-619436D01*
G01X263793D02*
X263286Y-619353D01*
X262843Y-619019D01*
X262463Y-618519D01*
X262210Y-617936D01*
X262083Y-617269D01*
Y-616603D01*
X262210Y-615936D01*
X262463Y-615353D01*
X262843Y-614853D01*
X263286Y-614519D01*
X263793Y-614436D01*
X264300Y-614519D01*
X264743Y-614853D01*
X265123Y-615353D01*
X265376Y-615936D01*
X265503Y-616603D01*
Y-617269D01*
X265376Y-617936D01*
X265123Y-618519D01*
X264743Y-619019D01*
X264300Y-619353D01*
X263793Y-619436D01*
G01X267626Y-618436D02*
X267943Y-618936D01*
X268323Y-619269D01*
X268766Y-619436D01*
X269273Y-619269D01*
X269653Y-618936D01*
X270033Y-618436D01*
X270160Y-617769D01*
Y-614436D01*
G01X275260Y-619436D02*
X272726D01*
Y-614436D01*
X275260D01*
G01X274246Y-616853D02*
X272726D01*
G01X280486Y-614853D02*
X280106Y-614603D01*
X279663Y-614436D01*
X279156D01*
X278586Y-614686D01*
X278143Y-615103D01*
X277826Y-615603D01*
X277573Y-616436D01*
X277510Y-617186D01*
X277636Y-617936D01*
X277826Y-618436D01*
X278206Y-618936D01*
X278650Y-619269D01*
X279093Y-619436D01*
X279536D01*
X279980Y-619269D01*
X280360Y-619019D01*
X280676Y-618686D01*
G01X284193Y-614436D02*
Y-619436D01*
G01X282736Y-614436D02*
X285650D01*
G01X289293Y-619603D02*
X289166Y-619519D01*
Y-619353D01*
X289293Y-619269D01*
X289420Y-619353D01*
Y-619519D01*
X289293Y-619603D01*
G01Y-617353D02*
X289166Y-617269D01*
Y-617103D01*
X289293Y-617019D01*
X289420Y-617103D01*
Y-617269D01*
X289293Y-617353D01*
G01X361693Y-659436D02*
Y-684436D01*
G01X364326Y-661936D02*
Y-666936D01*
X366860D01*
G01X369933Y-661936D02*
X371453D01*
G01X370693D02*
Y-666936D01*
G01X369933D02*
X371453D01*
G01X376300Y-664269D02*
X376553Y-664019D01*
X376743Y-663603D01*
X376870Y-663019D01*
X376743Y-662519D01*
X376490Y-662186D01*
X376046Y-661936D01*
X374336D01*
Y-666936D01*
X376426D01*
X376870Y-666603D01*
X377123Y-666103D01*
X377250Y-665519D01*
X377123Y-664936D01*
X376743Y-664436D01*
X376300Y-664269D01*
X374336D01*
G01X380893Y-667103D02*
X380766Y-667019D01*
Y-666853D01*
X380893Y-666769D01*
X381020Y-666853D01*
Y-667019D01*
X380893Y-667103D01*
G01Y-664853D02*
X380766Y-664769D01*
Y-664603D01*
X380893Y-664519D01*
X381020Y-664603D01*
Y-664769D01*
X380893Y-664853D01*
G01X404693Y-659436D02*
Y-684436D01*
G01Y-634436D02*
Y-659436D01*
G01X412706Y-687603D02*
X412813Y-687478D01*
X412893Y-687269D01*
X412946Y-686978D01*
X412893Y-686728D01*
X412786Y-686561D01*
X412600Y-686436D01*
X411880D01*
Y-688936D01*
X412760D01*
X412946Y-688769D01*
X413053Y-688519D01*
X413106Y-688228D01*
X413053Y-687936D01*
X412893Y-687686D01*
X412706Y-687603D01*
X411880D01*
G01X415173Y-688936D02*
Y-687269D01*
G01Y-687561D02*
X415066Y-687394D01*
X414906Y-687311D01*
X414720Y-687269D01*
X414533Y-687353D01*
X414373Y-687519D01*
X414266Y-687769D01*
X414213Y-688103D01*
X414266Y-688436D01*
X414373Y-688686D01*
X414533Y-688853D01*
X414720Y-688936D01*
X414906Y-688894D01*
X415066Y-688769D01*
X415173Y-688603D01*
G01X416493Y-688644D02*
X416626Y-688811D01*
X416813Y-688936D01*
X416973D01*
X417133Y-688853D01*
X417240Y-688728D01*
X417293Y-688561D01*
X417266Y-688311D01*
X417160Y-688186D01*
X416680Y-687936D01*
X416573Y-687644D01*
X416626Y-687436D01*
X416733Y-687311D01*
X416893Y-687269D01*
X417053Y-687311D01*
X417213Y-687436D01*
G01X418693Y-687811D02*
X419546D01*
X419466Y-687519D01*
X419333Y-687353D01*
X419146Y-687269D01*
X418960Y-687311D01*
X418800Y-687436D01*
X418693Y-687728D01*
X418640Y-687978D01*
Y-688228D01*
X418693Y-688478D01*
X418826Y-688728D01*
X418986Y-688894D01*
X419173Y-688936D01*
X419360Y-688853D01*
X419546Y-688603D01*
G01X420813Y-688936D02*
Y-686436D01*
G01Y-687686D02*
X420946Y-687436D01*
X421106Y-687311D01*
X421266Y-687269D01*
X421506Y-687353D01*
X421666Y-687519D01*
X421773Y-687811D01*
Y-688144D01*
X421720Y-688478D01*
X421613Y-688728D01*
X421426Y-688894D01*
X421266Y-688936D01*
X421106Y-688894D01*
X420946Y-688769D01*
X420813Y-688561D01*
G01X423493Y-688936D02*
X423333Y-688894D01*
X423173Y-688728D01*
X423066Y-688436D01*
X423013Y-688103D01*
X423066Y-687769D01*
X423173Y-687478D01*
X423333Y-687311D01*
X423493Y-687269D01*
X423653Y-687311D01*
X423813Y-687478D01*
X423920Y-687769D01*
X423946Y-688103D01*
X423920Y-688436D01*
X423813Y-688728D01*
X423653Y-688894D01*
X423493Y-688936D01*
G01X426173D02*
Y-687269D01*
G01Y-687561D02*
X426066Y-687394D01*
X425906Y-687311D01*
X425720Y-687269D01*
X425533Y-687353D01*
X425373Y-687519D01*
X425266Y-687769D01*
X425213Y-688103D01*
X425266Y-688436D01*
X425373Y-688686D01*
X425533Y-688853D01*
X425720Y-688936D01*
X425906Y-688894D01*
X426066Y-688769D01*
X426173Y-688603D01*
G01X427520Y-688936D02*
Y-687269D01*
G01Y-687603D02*
X427653Y-687436D01*
X427786Y-687311D01*
X427973Y-687269D01*
X428106Y-687311D01*
X428266Y-687436D01*
G01X430573Y-686436D02*
Y-688936D01*
G01Y-688561D02*
X430466Y-688769D01*
X430306Y-688894D01*
X430120Y-688936D01*
X429906Y-688853D01*
X429746Y-688644D01*
X429640Y-688394D01*
X429613Y-688103D01*
X429640Y-687811D01*
X429746Y-687561D01*
X429906Y-687353D01*
X430120Y-687269D01*
X430306Y-687311D01*
X430440Y-687394D01*
X430573Y-687561D01*
G01X433960Y-688936D02*
Y-686436D01*
X434626D01*
X434840Y-686561D01*
X434973Y-686728D01*
X435026Y-687061D01*
X434973Y-687394D01*
X434813Y-687603D01*
X434626Y-687728D01*
X433960D01*
G01X434626D02*
X435026Y-688936D01*
G01X436293Y-687811D02*
X437146D01*
X437066Y-687519D01*
X436933Y-687353D01*
X436746Y-687269D01*
X436560Y-687311D01*
X436400Y-687436D01*
X436293Y-687728D01*
X436240Y-687978D01*
Y-688228D01*
X436293Y-688478D01*
X436426Y-688728D01*
X436586Y-688894D01*
X436773Y-688936D01*
X436960Y-688853D01*
X437146Y-688603D01*
G01X438413Y-687269D02*
X438893Y-688936D01*
X439373Y-687269D01*
G01X441093Y-689019D02*
X441040Y-688978D01*
Y-688894D01*
X441093Y-688853D01*
X441146Y-688894D01*
Y-688978D01*
X441093Y-689019D01*
G01X443613Y-688936D02*
Y-686436D01*
X442626Y-688228D01*
X443960D01*
G01X444826Y-688936D02*
X445493Y-686436D01*
X446160Y-688936D01*
G01X445920Y-688061D02*
X445066D01*
G01X408593Y-661936D02*
Y-666936D01*
G01X407136Y-661936D02*
X410050D01*
G01X413693Y-666936D02*
X413313Y-666853D01*
X412933Y-666519D01*
X412680Y-665936D01*
X412553Y-665269D01*
X412680Y-664603D01*
X412933Y-664019D01*
X413313Y-663686D01*
X413693Y-663603D01*
X414073Y-663686D01*
X414453Y-664019D01*
X414706Y-664603D01*
X414770Y-665269D01*
X414706Y-665936D01*
X414453Y-666519D01*
X414073Y-666853D01*
X413693Y-666936D01*
G01X418793D02*
X418413Y-666853D01*
X418033Y-666519D01*
X417780Y-665936D01*
X417653Y-665269D01*
X417780Y-664603D01*
X418033Y-664019D01*
X418413Y-663686D01*
X418793Y-663603D01*
X419173Y-663686D01*
X419553Y-664019D01*
X419806Y-664603D01*
X419870Y-665269D01*
X419806Y-665936D01*
X419553Y-666519D01*
X419173Y-666853D01*
X418793Y-666936D01*
G01X423893D02*
Y-661936D01*
G01X428993Y-667103D02*
X428866Y-667019D01*
Y-666853D01*
X428993Y-666769D01*
X429120Y-666853D01*
Y-667019D01*
X428993Y-667103D01*
G01Y-664853D02*
X428866Y-664769D01*
Y-664603D01*
X428993Y-664519D01*
X429120Y-664603D01*
Y-664769D01*
X428993Y-664853D01*
G01X407326Y-641936D02*
Y-636936D01*
X408910D01*
X409416Y-637186D01*
X409733Y-637519D01*
X409860Y-638186D01*
X409733Y-638853D01*
X409353Y-639269D01*
X408910Y-639519D01*
X407326D01*
G01X408910D02*
X409860Y-641936D01*
G01X414960D02*
X412426D01*
Y-636936D01*
X414960D01*
G01X413946Y-639353D02*
X412426D01*
G01X417210Y-636936D02*
X418793Y-641936D01*
X420376Y-636936D01*
G01X423893Y-642103D02*
X423766Y-642019D01*
Y-641853D01*
X423893Y-641769D01*
X424020Y-641853D01*
Y-642019D01*
X423893Y-642103D01*
G01Y-639853D02*
X423766Y-639769D01*
Y-639603D01*
X423893Y-639519D01*
X424020Y-639603D01*
Y-639769D01*
X423893Y-639853D01*
G01X2010999Y-388000D02*
Y1475775D01*
X-407000D01*
Y-386798D01*
Y-755294D01*
Y-793716D01*
X-368578D01*
X1942346D01*
X2010999D01*
Y-725063D01*
Y-388000D01*
G01X-42602Y-671096D02*
X-41975Y-671621D01*
X-41270Y-671936D01*
X-40644D01*
X-40017Y-671621D01*
X-39547Y-671096D01*
X-39312Y-670361D01*
X-39469Y-669626D01*
X-39860Y-668996D01*
X-40565Y-668576D01*
X-41505Y-668366D01*
X-42054Y-667946D01*
X-42289Y-667211D01*
X-42132Y-666476D01*
X-41740Y-665951D01*
X-41192Y-665636D01*
X-40644D01*
X-40095Y-665846D01*
X-39625Y-666371D01*
G01X-36302Y-671936D02*
Y-665636D01*
G01X-33012D02*
Y-671936D01*
G01Y-668786D02*
X-36302D01*
G01X-29297Y-665636D02*
X-27417D01*
G01X-28357D02*
Y-671936D01*
G01X-29297D02*
X-27417D01*
G01X-20490D02*
X-23624D01*
Y-665636D01*
X-20490D01*
G01X-21744Y-668681D02*
X-23624D01*
G01X-17559Y-671936D02*
Y-665636D01*
X-13955Y-671936D01*
Y-665636D01*
G01X-9614Y-673091D02*
X-9300Y-671726D01*
G01X-3157Y-665636D02*
Y-671936D01*
G01X-4959Y-665636D02*
X-1355D01*
G01X1185Y-671936D02*
X3143Y-665636D01*
X5101Y-671936D01*
G01X4396Y-669731D02*
X1890D01*
G01X8503Y-665636D02*
X10383D01*
G01X9443D02*
Y-671936D01*
G01X8503D02*
X10383D01*
G01X13393Y-665636D02*
X14490Y-671936D01*
X15743Y-665636D01*
X16996Y-671936D01*
X18093Y-665636D01*
G01X20085Y-671936D02*
X22043Y-665636D01*
X24001Y-671936D01*
G01X23296Y-669731D02*
X20790D01*
G01X26541Y-671936D02*
Y-665636D01*
X30145Y-671936D01*
Y-665636D01*
G01X39376Y-671936D02*
Y-665636D01*
X41335D01*
X41961Y-665951D01*
X42353Y-666371D01*
X42510Y-667211D01*
X42353Y-668051D01*
X41883Y-668576D01*
X41335Y-668891D01*
X39376D01*
G01X41335D02*
X42510Y-671936D01*
G01X47243Y-672146D02*
X47086Y-672041D01*
Y-671831D01*
X47243Y-671726D01*
X47400Y-671831D01*
Y-672041D01*
X47243Y-672146D01*
G01X53543Y-671936D02*
X52916Y-671831D01*
X52368Y-671411D01*
X51898Y-670781D01*
X51585Y-670046D01*
X51428Y-669206D01*
Y-668366D01*
X51585Y-667526D01*
X51898Y-666791D01*
X52368Y-666161D01*
X52916Y-665741D01*
X53543Y-665636D01*
X54170Y-665741D01*
X54718Y-666161D01*
X55188Y-666791D01*
X55501Y-667526D01*
X55658Y-668366D01*
Y-669206D01*
X55501Y-670046D01*
X55188Y-670781D01*
X54718Y-671411D01*
X54170Y-671831D01*
X53543Y-671936D01*
G01X59843Y-672146D02*
X59686Y-672041D01*
Y-671831D01*
X59843Y-671726D01*
X60000Y-671831D01*
Y-672041D01*
X59843Y-672146D01*
G01X67866Y-666161D02*
X67396Y-665846D01*
X66848Y-665636D01*
X66221D01*
X65516Y-665951D01*
X64968Y-666476D01*
X64576Y-667106D01*
X64263Y-668156D01*
X64185Y-669101D01*
X64341Y-670046D01*
X64576Y-670676D01*
X65046Y-671306D01*
X65595Y-671726D01*
X66143Y-671936D01*
X66691D01*
X67240Y-671726D01*
X67710Y-671411D01*
X68101Y-670991D01*
G01X72443Y-672146D02*
X72286Y-672041D01*
Y-671831D01*
X72443Y-671726D01*
X72600Y-671831D01*
Y-672041D01*
X72443Y-672146D01*
G01X-42680Y-661936D02*
Y-655636D01*
G01X-39704D02*
X-42680Y-659521D01*
G01X-39234Y-661936D02*
X-41349Y-657736D01*
G01X-36380Y-655636D02*
Y-660151D01*
X-36067Y-661096D01*
X-35440Y-661726D01*
X-34657Y-661936D01*
X-33874Y-661726D01*
X-33247Y-661096D01*
X-32934Y-660151D01*
Y-655636D01*
G01X-26790Y-661936D02*
X-29924D01*
Y-655636D01*
X-26790D01*
G01X-28044Y-658681D02*
X-29924D01*
G01X-22997Y-655636D02*
X-21117D01*
G01X-22057D02*
Y-661936D01*
G01X-22997D02*
X-21117D01*
G01X-11102Y-661096D02*
X-10475Y-661621D01*
X-9770Y-661936D01*
X-9144D01*
X-8517Y-661621D01*
X-8047Y-661096D01*
X-7812Y-660361D01*
X-7969Y-659626D01*
X-8360Y-658996D01*
X-9065Y-658576D01*
X-10005Y-658366D01*
X-10554Y-657946D01*
X-10789Y-657211D01*
X-10632Y-656476D01*
X-10240Y-655951D01*
X-9692Y-655636D01*
X-9144D01*
X-8595Y-655846D01*
X-8125Y-656371D01*
G01X-4802Y-661936D02*
Y-655636D01*
G01X-1512D02*
Y-661936D01*
G01Y-658786D02*
X-4802D01*
G01X1185Y-661936D02*
X3143Y-655636D01*
X5101Y-661936D01*
G01X4396Y-659731D02*
X1890D01*
G01X7641Y-661936D02*
Y-655636D01*
X11245Y-661936D01*
Y-655636D01*
G01X20398Y-661936D02*
Y-655636D01*
G01X23688D02*
Y-661936D01*
G01Y-658786D02*
X20398D01*
G01X26698Y-661096D02*
X27325Y-661621D01*
X28030Y-661936D01*
X28656D01*
X29283Y-661621D01*
X29753Y-661096D01*
X29988Y-660361D01*
X29831Y-659626D01*
X29440Y-658996D01*
X28735Y-658576D01*
X27795Y-658366D01*
X27246Y-657946D01*
X27011Y-657211D01*
X27168Y-656476D01*
X27560Y-655951D01*
X28108Y-655636D01*
X28656D01*
X29205Y-655846D01*
X29675Y-656371D01*
G01X33703Y-655636D02*
X35583D01*
G01X34643D02*
Y-661936D01*
G01X33703D02*
X35583D01*
G01X38985D02*
X40943Y-655636D01*
X42901Y-661936D01*
G01X42196Y-659731D02*
X39690D01*
G01X45441Y-661936D02*
Y-655636D01*
X49045Y-661936D01*
Y-655636D01*
G01X54013Y-658786D02*
X55580D01*
Y-660676D01*
X55110Y-661306D01*
X54561Y-661726D01*
X53778Y-661936D01*
X52995Y-661726D01*
X52446Y-661306D01*
X51976Y-660676D01*
X51663Y-659941D01*
X51506Y-659101D01*
Y-658366D01*
X51663Y-657736D01*
X51976Y-657001D01*
X52446Y-656371D01*
X52916Y-655951D01*
X53543Y-655636D01*
X54091D01*
X54718Y-655846D01*
X55188Y-656266D01*
G01X59686Y-663091D02*
X60000Y-661726D01*
G01X66143Y-655636D02*
Y-661936D01*
G01X64341Y-655636D02*
X67945D01*
G01X70485Y-661936D02*
X72443Y-655636D01*
X74401Y-661936D01*
G01X73696Y-659731D02*
X71190D01*
G01X78743Y-661936D02*
X78116Y-661831D01*
X77568Y-661411D01*
X77098Y-660781D01*
X76785Y-660046D01*
X76628Y-659206D01*
Y-658366D01*
X76785Y-657526D01*
X77098Y-656791D01*
X77568Y-656161D01*
X78116Y-655741D01*
X78743Y-655636D01*
X79370Y-655741D01*
X79918Y-656161D01*
X80388Y-656791D01*
X80701Y-657526D01*
X80858Y-658366D01*
Y-659206D01*
X80701Y-660046D01*
X80388Y-660781D01*
X79918Y-661411D01*
X79370Y-661831D01*
X78743Y-661936D01*
G01X91343D02*
Y-659101D01*
X89776Y-655636D01*
G01X92910D02*
X91343Y-659101D01*
G01X95920Y-655636D02*
Y-660151D01*
X96233Y-661096D01*
X96860Y-661726D01*
X97643Y-661936D01*
X98426Y-661726D01*
X99053Y-661096D01*
X99366Y-660151D01*
Y-655636D01*
G01X101985Y-661936D02*
X103943Y-655636D01*
X105901Y-661936D01*
G01X105196Y-659731D02*
X102690D01*
G01X108441Y-661936D02*
Y-655636D01*
X112045Y-661936D01*
Y-655636D01*
G01X-42759Y-651936D02*
Y-645636D01*
X-39155Y-651936D01*
Y-645636D01*
G01X-34657Y-651936D02*
X-35284Y-651831D01*
X-35832Y-651411D01*
X-36302Y-650781D01*
X-36615Y-650046D01*
X-36772Y-649206D01*
Y-648366D01*
X-36615Y-647526D01*
X-36302Y-646791D01*
X-35832Y-646161D01*
X-35284Y-645741D01*
X-34657Y-645636D01*
X-34030Y-645741D01*
X-33482Y-646161D01*
X-33012Y-646791D01*
X-32699Y-647526D01*
X-32542Y-648366D01*
Y-649206D01*
X-32699Y-650046D01*
X-33012Y-650781D01*
X-33482Y-651411D01*
X-34030Y-651831D01*
X-34657Y-651936D01*
G01X-28357Y-652146D02*
X-28514Y-652041D01*
Y-651831D01*
X-28357Y-651726D01*
X-28200Y-651831D01*
Y-652041D01*
X-28357Y-652146D01*
G01X-22057Y-651936D02*
Y-645636D01*
X-22997Y-646896D01*
G01Y-651936D02*
X-21117D01*
G01X-15757D02*
X-15209Y-651831D01*
X-14582Y-651516D01*
X-14190Y-650991D01*
X-14034Y-650256D01*
X-14190Y-649521D01*
X-14660Y-648891D01*
X-15365Y-648576D01*
X-16149D01*
X-16619Y-648366D01*
X-17010Y-647841D01*
X-17167Y-647106D01*
X-16932Y-646371D01*
X-16384Y-645846D01*
X-15757Y-645636D01*
X-15130Y-645846D01*
X-14582Y-646371D01*
X-14347Y-647106D01*
X-14504Y-647841D01*
X-14895Y-648366D01*
X-15365Y-648576D01*
X-16149D01*
X-16854Y-648891D01*
X-17324Y-649521D01*
X-17480Y-650256D01*
X-17324Y-650991D01*
X-16932Y-651516D01*
X-16305Y-651831D01*
X-15757Y-651936D01*
G01X-9457D02*
X-8909Y-651831D01*
X-8282Y-651516D01*
X-7890Y-650991D01*
X-7734Y-650256D01*
X-7890Y-649521D01*
X-8360Y-648891D01*
X-9065Y-648576D01*
X-9849D01*
X-10319Y-648366D01*
X-10710Y-647841D01*
X-10867Y-647106D01*
X-10632Y-646371D01*
X-10084Y-645846D01*
X-9457Y-645636D01*
X-8830Y-645846D01*
X-8282Y-646371D01*
X-8047Y-647106D01*
X-8204Y-647841D01*
X-8595Y-648366D01*
X-9065Y-648576D01*
X-9849D01*
X-10554Y-648891D01*
X-11024Y-649521D01*
X-11180Y-650256D01*
X-11024Y-650991D01*
X-10632Y-651516D01*
X-10005Y-651831D01*
X-9457Y-651936D01*
G01X-3314Y-653091D02*
X-3000Y-651726D01*
G01X793Y-645636D02*
X1890Y-651936D01*
X3143Y-645636D01*
X4396Y-651936D01*
X5493Y-645636D01*
G01X11010Y-651936D02*
X7876D01*
Y-645636D01*
X11010D01*
G01X9756Y-648681D02*
X7876D01*
G01X13941Y-651936D02*
Y-645636D01*
X17545Y-651936D01*
Y-645636D01*
G01X26698Y-651936D02*
Y-645636D01*
G01X29988D02*
Y-651936D01*
G01Y-648786D02*
X26698D01*
G01X32293Y-645636D02*
X33390Y-651936D01*
X34643Y-645636D01*
X35896Y-651936D01*
X36993Y-645636D01*
G01X38985Y-651936D02*
X40943Y-645636D01*
X42901Y-651936D01*
G01X42196Y-649731D02*
X39690D01*
G01X52055Y-646686D02*
X52525Y-646056D01*
X53073Y-645741D01*
X53700Y-645636D01*
X54483Y-645846D01*
X55031Y-646371D01*
X55188Y-647001D01*
X55110Y-647631D01*
X54796Y-648156D01*
X53230Y-649206D01*
X52525Y-649941D01*
X52055Y-650991D01*
X51898Y-651936D01*
X55188D01*
G01X58041D02*
Y-645636D01*
X61645Y-651936D01*
Y-645636D01*
G01X64420Y-651936D02*
Y-645636D01*
X65986D01*
X66613Y-645951D01*
X67083Y-646371D01*
X67475Y-647001D01*
X67788Y-647736D01*
X67866Y-648786D01*
X67788Y-649836D01*
X67475Y-650571D01*
X67083Y-651201D01*
X66613Y-651621D01*
X65986Y-651936D01*
X64420D01*
G01X77176D02*
Y-645636D01*
X79135D01*
X79761Y-645951D01*
X80153Y-646371D01*
X80310Y-647211D01*
X80153Y-648051D01*
X79683Y-648576D01*
X79135Y-648891D01*
X77176D01*
G01X79135D02*
X80310Y-651936D01*
G01X83320D02*
Y-645636D01*
X84886D01*
X85513Y-645951D01*
X85983Y-646371D01*
X86375Y-647001D01*
X86688Y-647736D01*
X86766Y-648786D01*
X86688Y-649836D01*
X86375Y-650571D01*
X85983Y-651201D01*
X85513Y-651621D01*
X84886Y-651936D01*
X83320D01*
G01X91343Y-652146D02*
X91186Y-652041D01*
Y-651831D01*
X91343Y-651726D01*
X91500Y-651831D01*
Y-652041D01*
X91343Y-652146D01*
G01X-18657Y-639236D02*
X-21177Y-638819D01*
X-23382Y-637153D01*
X-25272Y-634653D01*
X-26532Y-631736D01*
X-27162Y-628403D01*
Y-625069D01*
X-26532Y-621736D01*
X-25272Y-618819D01*
X-23382Y-616320D01*
X-21177Y-614653D01*
X-18657Y-614236D01*
X-16137Y-614653D01*
X-13932Y-616320D01*
X-12042Y-618819D01*
X-10782Y-621736D01*
X-10152Y-625069D01*
Y-628403D01*
X-10782Y-631736D01*
X-12042Y-634653D01*
X-13932Y-637153D01*
X-16137Y-638819D01*
X-18657Y-639236D01*
G01X-16137Y-632569D02*
X-12357Y-639236D01*
G01X1188Y-622570D02*
Y-634236D01*
X2448Y-637153D01*
X4338Y-638819D01*
X6543Y-639236D01*
X8748Y-638819D01*
X10638Y-637153D01*
X11898Y-634236D01*
G01Y-639236D02*
Y-622570D01*
G01X37413Y-639236D02*
Y-622570D01*
G01Y-625486D02*
X36153Y-623820D01*
X34263Y-622986D01*
X32058Y-622570D01*
X29853Y-623403D01*
X27963Y-625069D01*
X26703Y-627570D01*
X26073Y-630903D01*
X26703Y-634236D01*
X27963Y-636737D01*
X29853Y-638403D01*
X32058Y-639236D01*
X34263Y-638819D01*
X36153Y-637570D01*
X37413Y-635903D01*
G01X51588Y-639236D02*
Y-622570D01*
G01Y-626736D02*
X52848Y-624653D01*
X54738Y-622986D01*
X57258Y-622570D01*
X59463Y-622986D01*
X61353Y-624653D01*
X62298Y-627570D01*
Y-639236D01*
G01X82143Y-614236D02*
Y-639236D01*
G01X77733Y-622570D02*
X86553D01*
G01X113013Y-639236D02*
Y-622570D01*
G01Y-625486D02*
X111753Y-623820D01*
X109863Y-622986D01*
X107658Y-622570D01*
X105453Y-623403D01*
X103563Y-625069D01*
X102303Y-627570D01*
X101673Y-630903D01*
X102303Y-634236D01*
X103563Y-636737D01*
X105453Y-638403D01*
X107658Y-639236D01*
X109863Y-638819D01*
X111753Y-637570D01*
X113013Y-635903D01*
G01X152693Y-618936D02*
Y-626936D01*
X156693D01*
G01X164493D02*
Y-621603D01*
G01Y-622536D02*
X164093Y-622003D01*
X163493Y-621736D01*
X162793Y-621603D01*
X162093Y-621869D01*
X161493Y-622403D01*
X161093Y-623203D01*
X160893Y-624269D01*
X161093Y-625336D01*
X161493Y-626136D01*
X162093Y-626669D01*
X162793Y-626936D01*
X163493Y-626803D01*
X164093Y-626403D01*
X164493Y-625870D01*
G01X168593Y-629336D02*
X169193Y-629603D01*
X169993Y-629336D01*
X170493Y-628803D01*
X170893Y-628136D01*
X171493Y-626003D01*
X172793Y-621603D01*
G01X169593D02*
X171493Y-626003D01*
G01X177193Y-623336D02*
X180393D01*
X180093Y-622403D01*
X179593Y-621869D01*
X178893Y-621603D01*
X178193Y-621736D01*
X177593Y-622136D01*
X177193Y-623069D01*
X176993Y-623870D01*
Y-624669D01*
X177193Y-625469D01*
X177693Y-626269D01*
X178293Y-626803D01*
X178993Y-626936D01*
X179693Y-626669D01*
X180393Y-625870D01*
G01X185293Y-626936D02*
Y-621603D01*
G01Y-622669D02*
X185793Y-622136D01*
X186293Y-621736D01*
X186993Y-621603D01*
X187493Y-621736D01*
X188093Y-622136D01*
G01X164193Y-651936D02*
Y-643936D01*
X166593D01*
X167393Y-644336D01*
X167993Y-645269D01*
X168193Y-646336D01*
X167993Y-647403D01*
X167493Y-648203D01*
X166593Y-648603D01*
X164193D01*
G01X171693Y-651936D02*
X174193Y-643936D01*
X176693Y-651936D01*
G01X175793Y-649136D02*
X172593D01*
G01X180093Y-650870D02*
X180893Y-651536D01*
X181793Y-651936D01*
X182593D01*
X183393Y-651536D01*
X183993Y-650870D01*
X184293Y-649936D01*
X184093Y-649003D01*
X183593Y-648203D01*
X182693Y-647669D01*
X181493Y-647403D01*
X180793Y-646869D01*
X180493Y-645936D01*
X180693Y-645003D01*
X181193Y-644336D01*
X181893Y-643936D01*
X182593D01*
X183293Y-644203D01*
X183893Y-644869D01*
G01X190193Y-643936D02*
Y-651936D01*
G01X187893Y-643936D02*
X192493D01*
G01X196893Y-649269D02*
X199493D01*
G01X206193Y-643936D02*
Y-651936D01*
G01X203893Y-643936D02*
X208493D01*
G01X214193Y-651936D02*
X213393Y-651803D01*
X212693Y-651269D01*
X212093Y-650469D01*
X211693Y-649536D01*
X211493Y-648469D01*
Y-647403D01*
X211693Y-646336D01*
X212093Y-645403D01*
X212693Y-644603D01*
X213393Y-644069D01*
X214193Y-643936D01*
X214993Y-644069D01*
X215693Y-644603D01*
X216293Y-645403D01*
X216693Y-646336D01*
X216893Y-647403D01*
Y-648469D01*
X216693Y-649536D01*
X216293Y-650469D01*
X215693Y-651269D01*
X214993Y-651803D01*
X214193Y-651936D01*
G01X220193D02*
Y-643936D01*
X222593D01*
X223393Y-644336D01*
X223993Y-645269D01*
X224193Y-646336D01*
X223993Y-647403D01*
X223493Y-648203D01*
X222593Y-648603D01*
X220193D01*
G01X173993Y-676936D02*
Y-668936D01*
G01X177793D02*
X173993Y-673870D01*
G01X178393Y-676936D02*
X175693Y-671603D01*
G01X185993Y-676936D02*
Y-671603D01*
G01Y-672536D02*
X185593Y-672003D01*
X184993Y-671736D01*
X184293Y-671603D01*
X183593Y-671869D01*
X182993Y-672403D01*
X182593Y-673203D01*
X182393Y-674269D01*
X182593Y-675336D01*
X182993Y-676136D01*
X183593Y-676669D01*
X184293Y-676936D01*
X184993Y-676803D01*
X185593Y-676403D01*
X185993Y-675870D01*
G01X192193Y-671603D02*
Y-676936D01*
G01Y-669469D02*
X191993Y-669336D01*
Y-669069D01*
X192193Y-668936D01*
X192393Y-669069D01*
Y-669336D01*
X192193Y-669469D01*
G01X279293Y-670269D02*
X279893Y-669469D01*
X280593Y-669069D01*
X281393Y-668936D01*
X282393Y-669203D01*
X283093Y-669869D01*
X283293Y-670669D01*
X283193Y-671470D01*
X282793Y-672136D01*
X280793Y-673469D01*
X279893Y-674403D01*
X279293Y-675736D01*
X279093Y-676936D01*
X283293D01*
G01X289193Y-668936D02*
X288393Y-669203D01*
X287793Y-669869D01*
X287393Y-670669D01*
X287093Y-671736D01*
X286993Y-672936D01*
X287093Y-674136D01*
X287393Y-675203D01*
X287793Y-676003D01*
X288393Y-676669D01*
X289193Y-676936D01*
X289993Y-676669D01*
X290593Y-676003D01*
X290993Y-675203D01*
X291293Y-674136D01*
X291393Y-672936D01*
X291293Y-671736D01*
X290993Y-670669D01*
X290593Y-669869D01*
X289993Y-669203D01*
X289193Y-668936D01*
G01X295293Y-670269D02*
X295893Y-669469D01*
X296593Y-669069D01*
X297393Y-668936D01*
X298393Y-669203D01*
X299093Y-669869D01*
X299293Y-670669D01*
X299193Y-671470D01*
X298793Y-672136D01*
X296793Y-673469D01*
X295893Y-674403D01*
X295293Y-675736D01*
X295093Y-676936D01*
X299293D01*
G01X303293Y-670269D02*
X303893Y-669469D01*
X304593Y-669069D01*
X305393Y-668936D01*
X306393Y-669203D01*
X307093Y-669869D01*
X307293Y-670669D01*
X307193Y-671470D01*
X306793Y-672136D01*
X304793Y-673469D01*
X303893Y-674403D01*
X303293Y-675736D01*
X303093Y-676936D01*
X307293D01*
G01X311393Y-677203D02*
X314993Y-668936D01*
G01X321193Y-676936D02*
Y-668936D01*
X319993Y-670536D01*
G01Y-676936D02*
X322393D01*
G01X327293Y-670269D02*
X327893Y-669469D01*
X328593Y-669069D01*
X329393Y-668936D01*
X330393Y-669203D01*
X331093Y-669869D01*
X331293Y-670669D01*
X331193Y-671470D01*
X330793Y-672136D01*
X328793Y-673469D01*
X327893Y-674403D01*
X327293Y-675736D01*
X327093Y-676936D01*
X331293D01*
G01X335393Y-677203D02*
X338993Y-668936D01*
G01X345193D02*
X344393Y-669203D01*
X343793Y-669869D01*
X343393Y-670669D01*
X343093Y-671736D01*
X342993Y-672936D01*
X343093Y-674136D01*
X343393Y-675203D01*
X343793Y-676003D01*
X344393Y-676669D01*
X345193Y-676936D01*
X345993Y-676669D01*
X346593Y-676003D01*
X346993Y-675203D01*
X347293Y-674136D01*
X347393Y-672936D01*
X347293Y-671736D01*
X346993Y-670669D01*
X346593Y-669869D01*
X345993Y-669203D01*
X345193Y-668936D01*
G01X351493Y-676003D02*
X352193Y-676669D01*
X352993Y-676936D01*
X353793Y-676669D01*
X354493Y-675870D01*
X354993Y-674669D01*
X355193Y-673469D01*
Y-672003D01*
X354993Y-670803D01*
X354493Y-669736D01*
X353893Y-669203D01*
X353193Y-668936D01*
X352393Y-669203D01*
X351793Y-669736D01*
X351393Y-670536D01*
X351193Y-671603D01*
X351393Y-672536D01*
X351893Y-673469D01*
X352493Y-674003D01*
X353193Y-674136D01*
X353993Y-673870D01*
X354593Y-673203D01*
X355193Y-672003D01*
G01X278993Y-651936D02*
Y-643936D01*
X280993D01*
X281793Y-644336D01*
X282393Y-644869D01*
X282893Y-645669D01*
X283293Y-646603D01*
X283393Y-647936D01*
X283293Y-649269D01*
X282893Y-650203D01*
X282393Y-651003D01*
X281793Y-651536D01*
X280993Y-651936D01*
X278993D01*
G01X286693D02*
X289193Y-643936D01*
X291693Y-651936D01*
G01X290793Y-649136D02*
X287593D01*
G01X297193Y-643936D02*
X296393Y-644203D01*
X295793Y-644869D01*
X295393Y-645669D01*
X295093Y-646736D01*
X294993Y-647936D01*
X295093Y-649136D01*
X295393Y-650203D01*
X295793Y-651003D01*
X296393Y-651669D01*
X297193Y-651936D01*
X297993Y-651669D01*
X298593Y-651003D01*
X298993Y-650203D01*
X299293Y-649136D01*
X299393Y-647936D01*
X299293Y-646736D01*
X298993Y-645669D01*
X298593Y-644869D01*
X297993Y-644203D01*
X297193Y-643936D01*
G01X303293Y-651936D02*
Y-643936D01*
X307093D01*
G01X305693Y-647803D02*
X303293D01*
G01X313193Y-643936D02*
X312393Y-644203D01*
X311793Y-644869D01*
X311393Y-645669D01*
X311093Y-646736D01*
X310993Y-647936D01*
X311093Y-649136D01*
X311393Y-650203D01*
X311793Y-651003D01*
X312393Y-651669D01*
X313193Y-651936D01*
X313993Y-651669D01*
X314593Y-651003D01*
X314993Y-650203D01*
X315293Y-649136D01*
X315393Y-647936D01*
X315293Y-646736D01*
X314993Y-645669D01*
X314593Y-644869D01*
X313993Y-644203D01*
X313193Y-643936D01*
G01X321193D02*
Y-651936D01*
G01X318893Y-643936D02*
X323493D01*
G01X326593Y-651936D02*
Y-643936D01*
X329193Y-650603D01*
X331793Y-643936D01*
Y-651936D01*
G01X334993D02*
Y-643936D01*
X336993D01*
X337793Y-644336D01*
X338393Y-644869D01*
X338893Y-645669D01*
X339293Y-646603D01*
X339393Y-647936D01*
X339293Y-649269D01*
X338893Y-650203D01*
X338393Y-651003D01*
X337793Y-651536D01*
X336993Y-651936D01*
X334993D01*
G01X347393Y-644603D02*
X346793Y-644203D01*
X346093Y-643936D01*
X345293D01*
X344393Y-644336D01*
X343693Y-645003D01*
X343193Y-645803D01*
X342793Y-647136D01*
X342693Y-648336D01*
X342893Y-649536D01*
X343193Y-650336D01*
X343793Y-651136D01*
X344493Y-651669D01*
X345193Y-651936D01*
X345893D01*
X346593Y-651669D01*
X347193Y-651269D01*
X347693Y-650736D01*
G01X350993Y-651936D02*
Y-643936D01*
X352993D01*
X353793Y-644336D01*
X354393Y-644869D01*
X354893Y-645669D01*
X355293Y-646603D01*
X355393Y-647936D01*
X355293Y-649269D01*
X354893Y-650203D01*
X354393Y-651003D01*
X353793Y-651536D01*
X352993Y-651936D01*
X350993D01*
G01X361193Y-643936D02*
X360393Y-644203D01*
X359793Y-644869D01*
X359393Y-645669D01*
X359093Y-646736D01*
X358993Y-647936D01*
X359093Y-649136D01*
X359393Y-650203D01*
X359793Y-651003D01*
X360393Y-651669D01*
X361193Y-651936D01*
X361993Y-651669D01*
X362593Y-651003D01*
X362993Y-650203D01*
X363293Y-649136D01*
X363393Y-647936D01*
X363293Y-646736D01*
X362993Y-645669D01*
X362593Y-644869D01*
X361993Y-644203D01*
X361193Y-643936D01*
G01X298418Y-624819D02*
Y-618519D01*
X301394D01*
G01X300298Y-621564D02*
X298418D01*
G01X306206Y-618519D02*
X305579Y-618729D01*
X305109Y-619254D01*
X304796Y-619884D01*
X304561Y-620724D01*
X304483Y-621669D01*
X304561Y-622614D01*
X304796Y-623454D01*
X305109Y-624084D01*
X305579Y-624609D01*
X306206Y-624819D01*
X306833Y-624609D01*
X307303Y-624084D01*
X307616Y-623454D01*
X307851Y-622614D01*
X307929Y-621669D01*
X307851Y-620724D01*
X307616Y-619884D01*
X307303Y-619254D01*
X306833Y-618729D01*
X306206Y-618519D01*
G01X312506D02*
Y-624819D01*
G01X310704Y-618519D02*
X314308D01*
G01X316456Y-626919D02*
X321156D01*
G01X323069Y-624819D02*
Y-618519D01*
X325106Y-623769D01*
X327143Y-618519D01*
Y-624819D01*
G01X332816D02*
Y-620619D01*
G01Y-621354D02*
X332503Y-620934D01*
X332033Y-620724D01*
X331484Y-620619D01*
X330936Y-620829D01*
X330466Y-621249D01*
X330153Y-621879D01*
X329996Y-622719D01*
X330153Y-623559D01*
X330466Y-624189D01*
X330936Y-624609D01*
X331484Y-624819D01*
X332033Y-624714D01*
X332503Y-624399D01*
X332816Y-623979D01*
G01X336374Y-624819D02*
Y-620619D01*
G01Y-621669D02*
X336688Y-621144D01*
X337158Y-620724D01*
X337784Y-620619D01*
X338333Y-620724D01*
X338803Y-621144D01*
X339038Y-621879D01*
Y-624819D01*
G01X345416D02*
Y-620619D01*
G01Y-621354D02*
X345103Y-620934D01*
X344633Y-620724D01*
X344084Y-620619D01*
X343536Y-620829D01*
X343066Y-621249D01*
X342753Y-621879D01*
X342596Y-622719D01*
X342753Y-623559D01*
X343066Y-624189D01*
X343536Y-624609D01*
X344084Y-624819D01*
X344633Y-624714D01*
X345103Y-624399D01*
X345416Y-623979D01*
G01X349209Y-626394D02*
X349758Y-626814D01*
X350384Y-626919D01*
X350933Y-626814D01*
X351403Y-626289D01*
X351716Y-625554D01*
Y-620619D01*
G01Y-621459D02*
X351403Y-621039D01*
X350933Y-620724D01*
X350384Y-620619D01*
X349758Y-620829D01*
X349366Y-621249D01*
X349053Y-621984D01*
X348896Y-622719D01*
X348974Y-623349D01*
X349288Y-624084D01*
X349758Y-624609D01*
X350384Y-624819D01*
X350854Y-624714D01*
X351403Y-624294D01*
X351716Y-623874D01*
G01X355431Y-621984D02*
X357938D01*
X357703Y-621249D01*
X357311Y-620829D01*
X356763Y-620619D01*
X356214Y-620724D01*
X355744Y-621039D01*
X355431Y-621774D01*
X355274Y-622404D01*
Y-623034D01*
X355431Y-623664D01*
X355823Y-624294D01*
X356293Y-624714D01*
X356841Y-624819D01*
X357389Y-624609D01*
X357938Y-623979D01*
G01X360556Y-624819D02*
Y-620619D01*
G01Y-621774D02*
X360791Y-621249D01*
X361183Y-620829D01*
X361731Y-620619D01*
X362279Y-620829D01*
X362671Y-621249D01*
X362906Y-621774D01*
Y-624819D01*
G01Y-621774D02*
X363141Y-621249D01*
X363533Y-620829D01*
X364081Y-620619D01*
X364629Y-620829D01*
X365021Y-621249D01*
X365256Y-621879D01*
Y-624819D01*
G01X368031Y-621984D02*
X370538D01*
X370303Y-621249D01*
X369911Y-620829D01*
X369363Y-620619D01*
X368814Y-620724D01*
X368344Y-621039D01*
X368031Y-621774D01*
X367874Y-622404D01*
Y-623034D01*
X368031Y-623664D01*
X368423Y-624294D01*
X368893Y-624714D01*
X369441Y-624819D01*
X369989Y-624609D01*
X370538Y-623979D01*
G01X374174Y-624819D02*
Y-620619D01*
G01Y-621669D02*
X374488Y-621144D01*
X374958Y-620724D01*
X375584Y-620619D01*
X376133Y-620724D01*
X376603Y-621144D01*
X376838Y-621879D01*
Y-624819D01*
G01X381806Y-618519D02*
Y-624819D01*
G01X380709Y-620619D02*
X382903D01*
G01X385756Y-626919D02*
X390456D01*
G01X395033Y-621459D02*
X395346Y-621144D01*
X395581Y-620619D01*
X395738Y-619884D01*
X395581Y-619254D01*
X395268Y-618834D01*
X394719Y-618519D01*
X392604D01*
Y-624819D01*
X395189D01*
X395738Y-624399D01*
X396051Y-623769D01*
X396208Y-623034D01*
X396051Y-622299D01*
X395581Y-621669D01*
X395033Y-621459D01*
X392604D01*
G01X398983Y-624819D02*
Y-618519D01*
X400549D01*
X401176Y-618834D01*
X401646Y-619254D01*
X402038Y-619884D01*
X402351Y-620619D01*
X402429Y-621669D01*
X402351Y-622719D01*
X402038Y-623454D01*
X401646Y-624084D01*
X401176Y-624504D01*
X400549Y-624819D01*
X398983D01*
G01X367693Y-679936D02*
Y-671936D01*
X366493Y-673536D01*
G01Y-679936D02*
X368893D01*
G01X373793Y-676603D02*
X374493Y-675669D01*
X375093Y-675136D01*
X375893Y-674869D01*
X376593Y-675136D01*
X377093Y-675669D01*
X377493Y-676469D01*
X377593Y-677403D01*
X377493Y-678203D01*
X377093Y-679003D01*
X376493Y-679669D01*
X375793Y-679936D01*
X374993Y-679669D01*
X374293Y-678870D01*
X373893Y-677669D01*
X373793Y-676336D01*
X373993Y-674603D01*
X374293Y-673669D01*
X374793Y-672736D01*
X375493Y-672069D01*
X376193Y-671936D01*
X376893Y-672203D01*
X377393Y-672869D01*
G01X383693Y-680203D02*
X383493Y-680069D01*
Y-679803D01*
X383693Y-679669D01*
X383893Y-679803D01*
Y-680069D01*
X383693Y-680203D01*
G01X389793Y-676603D02*
X390493Y-675669D01*
X391093Y-675136D01*
X391893Y-674869D01*
X392593Y-675136D01*
X393093Y-675669D01*
X393493Y-676469D01*
X393593Y-677403D01*
X393493Y-678203D01*
X393093Y-679003D01*
X392493Y-679669D01*
X391793Y-679936D01*
X390993Y-679669D01*
X390293Y-678870D01*
X389893Y-677669D01*
X389793Y-676336D01*
X389993Y-674603D01*
X390293Y-673669D01*
X390793Y-672736D01*
X391493Y-672069D01*
X392193Y-671936D01*
X392893Y-672203D01*
X393393Y-672869D01*
G01X412693Y-679936D02*
Y-671936D01*
X411493Y-673536D01*
G01Y-679936D02*
X413893D01*
G01X420493D02*
X420693Y-678203D01*
X420993Y-676736D01*
X421393Y-675403D01*
X421893Y-673936D01*
X422693Y-671936D01*
X418693D01*
G01X428693Y-680203D02*
X428493Y-680069D01*
Y-679803D01*
X428693Y-679669D01*
X428893Y-679803D01*
Y-680069D01*
X428693Y-680203D01*
G01X434793Y-673269D02*
X435393Y-672469D01*
X436093Y-672069D01*
X436893Y-671936D01*
X437893Y-672203D01*
X438593Y-672869D01*
X438793Y-673669D01*
X438693Y-674470D01*
X438293Y-675136D01*
X436293Y-676469D01*
X435393Y-677403D01*
X434793Y-678736D01*
X434593Y-679936D01*
X438793D01*
G01X432493Y-654936D02*
Y-646936D01*
X434493D01*
X435293Y-647336D01*
X435893Y-647869D01*
X436393Y-648669D01*
X436793Y-649603D01*
X436893Y-650936D01*
X436793Y-652269D01*
X436393Y-653203D01*
X435893Y-654003D01*
X435293Y-654536D01*
X434493Y-654936D01*
X432493D01*
G54D21*
X17000Y319983D03*
X20205Y255620D03*
X21000Y319983D03*
X42392Y198770D03*
X46392D03*
X44375Y255593D03*
X44470Y266883D03*
X40500Y359983D03*
X47500Y354983D03*
X40500Y388483D03*
Y395483D03*
X40800Y426483D03*
X52500Y72983D03*
X52055Y126681D03*
X60400Y189883D03*
X51849Y206241D03*
X50392Y198770D03*
X61200Y279883D03*
X61000Y330983D03*
X63000Y405983D03*
X64000Y133183D03*
X75500Y157983D03*
X72800Y183783D03*
X65100Y279983D03*
X74500Y276983D03*
X64900Y330983D03*
X76500Y331113D03*
X68800Y331283D03*
X75000Y405983D03*
X66250Y421233D03*
X91925Y122079D03*
X92405Y134964D03*
X81500Y170383D03*
X83500Y272483D03*
X87500D03*
X79500D03*
X92500Y405983D03*
X88500D03*
X84500D03*
X108500Y41983D03*
X106800Y87983D03*
X101500Y260983D03*
X97300Y260783D03*
X100500Y405983D03*
X104500D03*
X108500D03*
X116500Y41983D03*
X120331Y242983D03*
X122500Y256683D03*
X121918Y331471D03*
X116500Y406083D03*
X119100Y399283D03*
X112500Y405983D03*
X126200Y82483D03*
X132900Y184183D03*
X138000Y210983D03*
X132398Y227675D03*
X128720Y227673D03*
X137918Y331471D03*
X125918D03*
X129300Y428983D03*
X145500Y143483D03*
X148387Y153198D03*
X148400Y167583D03*
X148370Y175233D03*
X142150Y187058D03*
X149500Y232483D03*
X145600Y238383D03*
X142300Y278683D03*
X141918Y331471D03*
X143945Y351631D03*
X147900Y351583D03*
X145200Y432433D03*
X143000Y422483D03*
X163673Y88713D03*
X159673D03*
X159120Y122103D03*
X156500Y135483D03*
X160032Y219702D03*
X153500Y231983D03*
X160973Y252494D03*
X164801Y260444D03*
X153918Y331471D03*
X165026Y346679D03*
X157600Y432483D03*
X161450D03*
X173097Y88713D03*
X169097D03*
X171900Y137883D03*
X177413Y252494D03*
X173992Y260444D03*
X169967D03*
X171276Y426679D03*
X181400Y432683D03*
X175100Y426383D03*
X183800Y122983D03*
X195983Y137852D03*
X188000Y137883D03*
X192000D03*
X183413Y253194D03*
X191538Y253319D03*
X187550Y262723D03*
X193750Y371233D03*
X210778Y111827D03*
X212757Y137852D03*
X208627D03*
X204063Y253269D03*
X211700Y432183D03*
X207300D03*
X215000Y43983D03*
X214785Y111825D03*
X221278Y137852D03*
X217262D03*
X225284D03*
X220600Y327783D03*
X213500Y388983D03*
X222800Y379258D03*
X226500Y406783D03*
X219600Y432183D03*
X215700D03*
X234600Y110983D03*
X229396Y137852D03*
X238500Y334983D03*
X242500Y343483D03*
X254332Y117141D03*
X243700Y109083D03*
X250212Y138770D03*
X246205D03*
X256128Y253162D03*
X250505Y253136D03*
X242940Y261449D03*
X269800Y105383D03*
X258339Y117141D03*
X271674Y148287D03*
X272037Y248435D03*
X269400Y284483D03*
X267000Y419883D03*
X271900Y426783D03*
X257900Y426683D03*
X261900D03*
X277000Y47483D03*
X285295Y123364D03*
X281250Y118983D03*
X281300Y111383D03*
X277200Y118983D03*
X275684Y148287D03*
X279582Y248635D03*
X273250Y275483D03*
X284475Y374991D03*
X290000Y65483D03*
X301936Y149355D03*
X292000Y293983D03*
X299000Y294483D03*
X316066Y105801D03*
X316700Y122883D03*
X309936Y149355D03*
X313936D03*
X305936D03*
X311000Y326483D03*
X329825Y278880D03*
X330900Y320383D03*
X337223Y233540D03*
X337600Y278883D03*
G54D12*
X22047Y46417D03*
X333466D03*
G54D105*
X238334Y373449D03*
Y369512D03*
Y365575D03*
Y381323D03*
Y377386D03*
X255382Y375417D03*
Y371481D03*
Y367543D03*
Y363606D03*
Y383292D03*
Y379355D03*
X303295Y373449D03*
Y369512D03*
Y365575D03*
Y381323D03*
Y377386D03*
X320343Y375417D03*
Y371481D03*
Y367543D03*
Y363606D03*
Y383292D03*
Y379355D03*
G54D30*
X33306Y196771D03*
Y195196D03*
Y193621D03*
Y192047D03*
Y201495D03*
Y199921D03*
Y198346D03*
G54D22*
X18609Y422600D03*
X32191D03*
G54D13*
X24016Y89331D03*
X330315D03*
G54D106*
X271500Y47559D03*
Y42441D03*
X264500D03*
Y45000D03*
Y47559D03*
X286000Y51941D03*
Y54500D03*
Y57059D03*
X293000D03*
Y51941D03*
G54D31*
X20500Y211000D03*
X27500D03*
X20500Y218000D03*
X27500D03*
X25000Y240500D03*
X32000D03*
X25000Y233500D03*
X32000D03*
X207750Y361100D03*
X199750D03*
X207595Y378154D03*
X199595D03*
X203750Y369900D03*
X203595Y386954D03*
G54D40*
X26768Y258807D03*
G54D50*
X36414Y254083D03*
G54D23*
X22638Y27520D03*
X40354D03*
X269095Y29095D03*
X286811D03*
X313977Y27520D03*
X331693D03*
G54D32*
X24100Y226000D03*
X29900D03*
X40915Y225958D03*
X35115D03*
X112300Y112300D03*
X118100D03*
X112300Y118500D03*
X118100D03*
X112300Y128500D03*
X118100D03*
X253508Y263492D03*
X247708D03*
X291380Y138297D03*
X297180D03*
X294009Y147731D03*
X288209D03*
G54D107*
X271066Y118077D03*
X263586D03*
Y127525D03*
X267326D03*
X271066D03*
G54D14*
X10470Y71500D03*
X12100Y438790D03*
X104000Y157600D03*
X269600Y337700D03*
X310800Y42000D03*
X323200Y451500D03*
G54D41*
X23100Y264300D03*
X38101Y239700D03*
X108000Y237200D03*
G54D51*
X34642Y251327D03*
G54D33*
X30148Y246113D03*
X30783Y264500D03*
X28183Y316900D03*
X19883Y328600D03*
X39983Y38000D03*
X45467Y214718D03*
X36783Y214700D03*
X46583Y241000D03*
X47383Y248800D03*
X39475Y246116D03*
X46583Y244900D03*
X37783Y264500D03*
X53699Y38500D03*
X54633Y211200D03*
X51783Y260800D03*
X49983Y328000D03*
Y324000D03*
Y344000D03*
Y348000D03*
Y364000D03*
Y368000D03*
Y372000D03*
Y376000D03*
Y380000D03*
Y384000D03*
X50383Y394350D03*
X66458Y116450D03*
X77502Y135866D03*
X81049Y118216D03*
X94473Y428020D03*
X118083Y102000D03*
Y107600D03*
X110983Y102000D03*
Y107500D03*
X117483Y123500D03*
X121783Y346400D03*
Y342500D03*
X118983Y415000D03*
X130483Y50000D03*
X136983Y201500D03*
X133483Y253700D03*
X132683Y261900D03*
X136083Y429000D03*
X152483Y142000D03*
X143483Y175200D03*
X143493Y179160D03*
X151577Y182594D03*
X139883Y348300D03*
Y351900D03*
X149563Y419250D03*
X166283Y112800D03*
X159388Y153077D03*
X158592Y182644D03*
X158699Y178679D03*
X158683Y174800D03*
X158733Y187354D03*
X158783Y191700D03*
X159483Y224000D03*
X158282Y313560D03*
X158283Y309700D03*
X160983Y350500D03*
X153483Y429000D03*
X174383Y272800D03*
X185983Y88000D03*
Y92000D03*
X189983Y267000D03*
X196983Y264810D03*
X187583Y294500D03*
X192183Y311100D03*
X210623Y244900D03*
X209783Y419600D03*
X217403Y102014D03*
X225103Y258930D03*
X225983Y296600D03*
Y300600D03*
X220883Y416000D03*
X236283Y319400D03*
X257283Y98600D03*
Y95100D03*
X255083Y110300D03*
X269944Y368610D03*
Y381075D03*
X284193Y93260D03*
X276703Y99350D03*
X286041Y138403D03*
X297483Y79500D03*
X291983Y100400D03*
X297743Y142907D03*
X300483Y311500D03*
X293208Y358508D03*
Y363008D03*
X292744Y387500D03*
X305983Y79500D03*
X308364Y273256D03*
X329110Y144423D03*
X324363Y275940D03*
X323142Y294816D03*
X337283Y70000D03*
X337308Y154911D03*
Y164911D03*
Y159911D03*
Y169911D03*
Y179911D03*
Y174911D03*
Y183926D03*
Y189911D03*
X336807Y292085D03*
G54D15*
X19500Y121603D03*
Y129083D03*
X18037Y311599D03*
Y304119D03*
X28000Y121603D03*
Y129083D03*
X34839Y311551D03*
Y304071D03*
X26438Y311575D03*
Y304095D03*
X36500Y121603D03*
X45000D03*
X36500Y129083D03*
X45000D03*
X43240Y311757D03*
Y304277D03*
X131000Y210260D03*
Y217740D03*
X220100Y80860D03*
Y88340D03*
X305320Y228803D03*
X313721Y228779D03*
X305320Y236283D03*
X313721Y236259D03*
X322122Y228755D03*
X330523Y228731D03*
X322122Y236235D03*
X330523Y236211D03*
X336500Y132260D03*
Y139740D03*
G54D42*
X28260Y322441D03*
Y325000D03*
Y327559D03*
X35740D03*
Y325000D03*
Y322441D03*
G54D108*
X295402Y45224D03*
Y41878D03*
G54D24*
X35256Y140183D03*
Y174347D03*
G54D60*
X73898Y24764D03*
X100472D03*
X127047D03*
X221142D03*
X247717D03*
G54D109*
X293630Y84000D03*
X297370D03*
X303130D03*
X306870D03*
G54D70*
X108776Y47760D03*
Y51500D03*
Y55240D03*
X118224Y47760D03*
Y55240D03*
X135824Y240260D03*
X126376D03*
X135824Y247740D03*
X126376Y244000D03*
Y247740D03*
G54D61*
X78031Y123474D03*
X74095D03*
X323795Y282404D03*
X319859D03*
G54D25*
X32914Y184247D03*
X21209Y259777D03*
X46984Y38000D03*
X45070Y58317D03*
X47203Y187525D03*
X45370Y191535D03*
X40233Y184311D03*
X45468Y210701D03*
X44388Y259638D03*
X39884Y317100D03*
X37984Y338000D03*
X40984Y348500D03*
Y352000D03*
X44484Y415700D03*
Y419700D03*
X37584Y411900D03*
Y415700D03*
X53700Y34873D03*
X54884Y220600D03*
X51784Y264600D03*
X49984Y332000D03*
Y336000D03*
Y340000D03*
Y387700D03*
X50384Y397850D03*
Y401350D03*
X92984Y255500D03*
X79484Y259200D03*
X92734Y417000D03*
Y412500D03*
X107484Y80000D03*
X112785Y62963D03*
Y66963D03*
X121784Y350300D03*
X129484Y54300D03*
X126484Y114000D03*
Y131000D03*
X150560Y187354D03*
X158884Y158300D03*
X158584Y163400D03*
X159184Y167100D03*
X158684Y171000D03*
X157284Y195700D03*
X159841Y212568D03*
X155924Y242750D03*
X158284Y301000D03*
Y297000D03*
Y305100D03*
X153584Y432600D03*
X180884Y272800D03*
X178984Y325200D03*
Y329200D03*
X177484Y432600D03*
X185984Y96000D03*
X195284Y111300D03*
X197054Y260830D03*
X186384Y300200D03*
Y304200D03*
X199584Y268700D03*
X205484Y273000D03*
X217404Y97984D03*
X225984Y304600D03*
X226624Y372400D03*
X226614Y383260D03*
X232684Y258200D03*
X249932Y257365D03*
X253297Y268403D03*
X243488Y313514D03*
X250484Y313500D03*
X243488Y319310D03*
X250484Y322000D03*
X261984Y110300D03*
X261384Y259900D03*
X269945Y364610D03*
Y385343D03*
X280234Y123250D03*
X272984Y399500D03*
X300484Y307000D03*
X291484Y372700D03*
X293209Y367508D03*
X292745Y391600D03*
X303484Y57000D03*
X311284Y134300D03*
X308365Y285092D03*
Y281088D03*
Y277100D03*
X307984Y311500D03*
X319084Y62700D03*
X329111Y148439D03*
X337284Y66000D03*
Y74000D03*
X337544Y125500D03*
X336784Y295900D03*
X332984Y358500D03*
Y376500D03*
Y367500D03*
Y372000D03*
Y363000D03*
Y381000D03*
Y385500D03*
G54D34*
X24996Y254083D03*
G54D16*
X16608Y190420D03*
X18000Y233084D03*
X42281Y206242D03*
X46307D03*
X40500Y233984D03*
X48440Y255594D03*
X40500Y373984D03*
Y366984D03*
Y380984D03*
Y402484D03*
X48600Y431984D03*
X44700D03*
X52500Y65984D03*
X63918Y126139D03*
X60090Y126144D03*
X61216Y228784D03*
X52440Y255594D03*
X63300Y260784D03*
X49938Y308780D03*
X55800Y330984D03*
X52500Y431984D03*
X56500D03*
X69200Y183784D03*
X65500D03*
X73400Y222684D03*
X77500D03*
X75400Y232884D03*
X65216Y228784D03*
X72500Y261484D03*
X67000Y405984D03*
X71000D03*
X88083Y124956D03*
X81500Y222684D03*
X91500Y272484D03*
X93500Y261984D03*
X86500Y261784D03*
X90804Y333304D03*
X79000Y405984D03*
X102800Y87984D03*
X100000Y95984D03*
X99700Y122084D03*
X95800D03*
X100400Y134984D03*
X96400D03*
X106800Y259584D03*
X99500Y272484D03*
X103500D03*
X95500D03*
X107400Y273384D03*
X103100Y331184D03*
X98000D03*
X98680Y428434D03*
X120500Y41984D03*
X112500D03*
X110800Y260184D03*
X119760Y271185D03*
X115260D03*
X111500Y270984D03*
X114800Y260784D03*
X111100Y279184D03*
X115260Y279185D03*
X119760D03*
X117918Y331472D03*
X113918D03*
X118800Y357184D03*
X129500Y143984D03*
X137525Y143811D03*
X133500Y143984D03*
X133000Y176484D03*
X129000D03*
X126500Y256684D03*
X124500Y264184D03*
X128760Y271185D03*
X124260D03*
X133000Y270984D03*
X124260Y279185D03*
X128760D03*
X129918Y331472D03*
X133918D03*
X141500Y143484D03*
X152434Y153199D03*
X141500Y241484D03*
X145918Y331472D03*
X149918D03*
X139900Y431984D03*
X155300Y104284D03*
X155530Y122104D03*
X164400Y122984D03*
X168000Y137984D03*
X160457Y145493D03*
X156430Y145465D03*
X160500Y205584D03*
X156028Y219703D03*
X157500Y231984D03*
X156973Y252495D03*
X165013D03*
X160713Y260513D03*
X156713D03*
X155000Y292484D03*
X165200Y320484D03*
X161026Y346680D03*
X178000Y107284D03*
X172632Y123010D03*
X168616D03*
X178186Y122710D03*
X180000Y137784D03*
X176000D03*
X178174Y261005D03*
X169026Y346680D03*
X173026D03*
X187272Y81937D03*
X191312D03*
X196065Y123010D03*
X191400D03*
X184000Y137884D03*
X183350Y262264D03*
X188000Y320884D03*
X193750Y363734D03*
Y379484D03*
Y388484D03*
X192334Y432236D03*
X211000Y43984D03*
X200000Y122984D03*
X210189Y123010D03*
X204000Y122984D03*
X199985Y137853D03*
X204120D03*
X207912Y253108D03*
X199810Y253270D03*
X209500Y275984D03*
X199405Y432236D03*
X203400Y432184D03*
X219000Y43984D03*
X214500Y93984D03*
X223300Y122984D03*
X214464Y123010D03*
X218200Y252084D03*
X221800D03*
X222300Y282084D03*
X221260Y313344D03*
X220600Y320984D03*
X226650Y379294D03*
X213500Y379484D03*
X237000Y44484D03*
X233000D03*
X242200Y122984D03*
X228600D03*
X238382Y123010D03*
X233511Y138053D03*
X242195Y137853D03*
X237655D03*
X239100Y253684D03*
X235100D03*
X228500Y334984D03*
Y347784D03*
X246000Y122984D03*
X252400Y280394D03*
X254010Y426698D03*
X265900Y112984D03*
X261300Y253284D03*
X268000Y426784D03*
X286000Y44484D03*
X281500D03*
X286000Y65484D03*
X277000Y78984D03*
X281000D03*
X285000D03*
X285295Y113870D03*
X277300Y108884D03*
X285295Y131451D03*
X277049Y131538D03*
X278028Y140298D03*
X272698Y140308D03*
X284100Y419784D03*
X290245Y44487D03*
X301936Y141256D03*
X288000Y293984D03*
X316066Y113869D03*
X313936Y141356D03*
X309936D03*
X305936D03*
X303077Y294698D03*
X307087D03*
X320872Y120186D03*
X317936Y149356D03*
X322000Y147984D03*
X333278Y148348D03*
X333839Y278881D03*
X333828Y286261D03*
X332500Y303284D03*
X336500D03*
G54D52*
X34642Y258807D03*
G54D43*
X23819Y339154D03*
Y349154D03*
Y359154D03*
Y369154D03*
Y379154D03*
Y389154D03*
Y399154D03*
X65709Y52244D03*
X75709Y42244D03*
Y52244D03*
X95709Y42244D03*
X85709D03*
X95709Y52244D03*
X85709D03*
G54D62*
X76063Y125049D03*
X74095Y129379D03*
X78031D03*
X321827Y283979D03*
X319859Y288309D03*
X323795D03*
G54D71*
X107969Y63302D03*
Y66648D03*
X114661Y63302D03*
Y66648D03*
G54D80*
X143118Y44803D03*
X194851D03*
G54D53*
X46925Y360000D03*
X50075D03*
G54D35*
X24996Y256051D03*
G54D17*
X16608Y187453D03*
X18000Y230117D03*
X42281Y203275D03*
X46307D03*
X40500Y231017D03*
X48440Y252627D03*
X40500Y371017D03*
Y364017D03*
Y378017D03*
Y399517D03*
X48600Y429017D03*
X44700D03*
X52500Y63017D03*
X63918Y123172D03*
X60090Y123177D03*
X61216Y225817D03*
X52440Y252627D03*
X63300Y257817D03*
X49938Y305813D03*
X55800Y328017D03*
X52500Y429017D03*
X56500D03*
X69200Y180817D03*
X65500D03*
X73400Y219717D03*
X77500D03*
X65216Y225817D03*
X75400Y229917D03*
X72500Y258517D03*
X67000Y403017D03*
X71000D03*
X88083Y121989D03*
X81500Y219717D03*
X91500Y269517D03*
X93500Y259017D03*
X86500Y258817D03*
X90804Y330337D03*
X79000Y403017D03*
X102800Y85017D03*
X100000Y93017D03*
X99700Y119117D03*
X95800D03*
X100400Y132017D03*
X96400D03*
X106800Y256617D03*
X99500Y269517D03*
X107400Y270417D03*
X103500Y269517D03*
X95500D03*
X103100Y328217D03*
X98000D03*
X98680Y425467D03*
X120500Y39017D03*
X112500D03*
X110800Y257217D03*
X119760Y268218D03*
X115260D03*
X111500Y268017D03*
X114800Y257817D03*
X111100Y276217D03*
X115260Y276218D03*
X119760D03*
X117918Y328505D03*
X113918D03*
X118800Y354217D03*
X129500Y141017D03*
X137525Y140844D03*
X133500Y141017D03*
X133000Y173517D03*
X129000D03*
X126500Y253717D03*
X124500Y261217D03*
X128760Y268218D03*
X124260D03*
X133000Y268017D03*
X124260Y276218D03*
X128760D03*
X129918Y328505D03*
X133918D03*
X141500Y140517D03*
X152434Y150232D03*
X141500Y238517D03*
X145918Y328505D03*
X149918D03*
X139900Y429017D03*
X155300Y101317D03*
X155530Y119137D03*
X164400Y120017D03*
X168000Y135017D03*
X160457Y142526D03*
X156430Y142498D03*
X160500Y202617D03*
X156028Y216736D03*
X157500Y229017D03*
X156973Y249528D03*
X160713Y257546D03*
X156713D03*
X165013Y249528D03*
X155000Y289517D03*
X165200Y317517D03*
X161026Y343713D03*
X178000Y104317D03*
X172632Y120043D03*
X168616D03*
X178186Y119743D03*
X180000Y134817D03*
X176000D03*
X178174Y258038D03*
X169026Y343713D03*
X173026D03*
X187272Y78970D03*
X191312D03*
X196065Y120043D03*
X191400D03*
X184000Y134917D03*
X183350Y259297D03*
X188000Y317917D03*
X193750Y360767D03*
Y376517D03*
Y385517D03*
X192334Y429269D03*
X211000Y41017D03*
X200000Y120017D03*
X210189Y120043D03*
X204000Y120017D03*
X199985Y134886D03*
X204120D03*
X207912Y250141D03*
X199810Y250303D03*
X209500Y273017D03*
X199405Y429269D03*
X203400Y429217D03*
X219000Y41017D03*
X214500Y91017D03*
X223300Y120017D03*
X214464Y120043D03*
X218200Y249117D03*
X221800D03*
X222300Y279117D03*
X221260Y310377D03*
X220600Y318017D03*
X226650Y376327D03*
X213500Y376517D03*
X237000Y41517D03*
X233000D03*
X242200Y120017D03*
X228600D03*
X238382Y120043D03*
X233511Y135086D03*
X242195Y134886D03*
X237655D03*
X239100Y250717D03*
X235100D03*
X228500Y332017D03*
Y344817D03*
X246000Y120017D03*
X252400Y277427D03*
X254010Y423731D03*
X265900Y110017D03*
X261300Y250317D03*
X268000Y423817D03*
X286000Y41517D03*
X281500D03*
X286000Y62517D03*
X277000Y76017D03*
X281000D03*
X285000D03*
X277300Y105917D03*
X285295Y110903D03*
Y128484D03*
X278028Y137331D03*
X272698Y137341D03*
X277049Y128571D03*
X284100Y416817D03*
X290245Y41520D03*
X301936Y138289D03*
X288000Y291017D03*
X316066Y110902D03*
X313936Y138389D03*
X309936D03*
X305936D03*
X303077Y291731D03*
X307087D03*
X320872Y117219D03*
X317936Y146389D03*
X322000Y145017D03*
X333278Y145381D03*
X333839Y275914D03*
X333828Y283294D03*
X332500Y300317D03*
X336500D03*
G54D44*
X23819Y409154D03*
X65709Y42244D03*
G54D26*
X22282Y197854D03*
G54D72*
X98976Y415200D03*
X108424D03*
G54D81*
X136319Y77244D03*
Y81181D03*
Y85118D03*
Y89055D03*
Y92992D03*
Y96929D03*
Y100866D03*
Y104803D03*
Y108740D03*
Y112677D03*
Y116614D03*
Y120551D03*
Y124488D03*
G54D36*
X28737Y258413D03*
X32673D03*
X30705D03*
X32673Y251721D03*
X28737D03*
G54D63*
X70354Y124261D03*
Y126230D03*
Y128198D03*
Y130167D03*
X81772D03*
Y128198D03*
Y126230D03*
Y124261D03*
X316118Y283191D03*
Y285160D03*
Y287128D03*
Y289097D03*
X327536Y285160D03*
Y283191D03*
Y289097D03*
Y287128D03*
G54D45*
X48038Y45897D03*
X45479D03*
X42920D03*
Y52897D03*
X48038D03*
G54D27*
X22282Y190078D03*
X33306Y203464D03*
G54D18*
X18242Y259777D03*
X29947Y184247D03*
X44017Y38000D03*
X42103Y58317D03*
X44236Y187525D03*
X42403Y191535D03*
X37266Y184311D03*
X42501Y210701D03*
X48817Y264600D03*
X41421Y259638D03*
X36917Y317100D03*
X47017Y332000D03*
X35017Y338000D03*
X47017Y336000D03*
Y340000D03*
X38017Y348500D03*
Y352000D03*
X47017Y387700D03*
X47417Y397850D03*
Y401350D03*
X41517Y415700D03*
Y419700D03*
X34617Y411900D03*
Y415700D03*
X50733Y34873D03*
X51917Y220600D03*
X76517Y259200D03*
X90017Y255500D03*
X89767Y417000D03*
Y412500D03*
X104517Y80000D03*
X109818Y62963D03*
Y66963D03*
X123517Y114000D03*
Y131000D03*
X118817Y350300D03*
X126517Y54300D03*
X147593Y187354D03*
X152957Y242750D03*
X150617Y432600D03*
X155917Y158300D03*
X155617Y163400D03*
X156217Y167100D03*
X155717Y171000D03*
X154317Y195700D03*
X156874Y212568D03*
X155317Y301000D03*
Y297000D03*
Y305100D03*
X183017Y96000D03*
X177917Y272800D03*
X176017Y325200D03*
Y329200D03*
X174517Y432600D03*
X192317Y111300D03*
X194087Y260830D03*
X196617Y268700D03*
X183417Y300200D03*
Y304200D03*
X202517Y273000D03*
X214437Y97984D03*
X223017Y304600D03*
X223657Y372400D03*
X223647Y383260D03*
X229717Y258200D03*
X240521Y313514D03*
Y319310D03*
X246965Y257365D03*
X250330Y268403D03*
X247517Y313500D03*
Y322000D03*
X259017Y110300D03*
X258417Y259900D03*
X266978Y364610D03*
Y385343D03*
X270017Y399500D03*
X277267Y123250D03*
X300517Y57000D03*
X297517Y307000D03*
X288517Y372700D03*
X290242Y367508D03*
X289778Y391600D03*
X316117Y62700D03*
X308317Y134300D03*
X305398Y285092D03*
Y281088D03*
Y277100D03*
X305017Y311500D03*
X326144Y148439D03*
X330017Y358500D03*
Y376500D03*
Y367500D03*
Y372000D03*
Y363000D03*
Y381000D03*
Y385500D03*
X334317Y66000D03*
Y74000D03*
X334577Y125500D03*
X333817Y295900D03*
G54D54*
X63898Y24764D03*
X90472D03*
X117047D03*
X211142D03*
X237717D03*
G54D90*
X155205Y52677D03*
G54D19*
X17000Y317016D03*
X20205Y252653D03*
X21000Y317016D03*
X42392Y195803D03*
X46392D03*
X44375Y252626D03*
X44470Y263916D03*
X40500Y357016D03*
X47500Y352016D03*
X40500Y385516D03*
Y392516D03*
X40800Y423516D03*
X52500Y70016D03*
X52055Y123714D03*
X50392Y195803D03*
X60400Y186916D03*
X51849Y203274D03*
X61200Y276916D03*
X61000Y328016D03*
X63000Y403016D03*
X64000Y130216D03*
X75500Y155016D03*
X72800Y180816D03*
X65100Y277016D03*
X74500Y274016D03*
X64900Y328016D03*
X76500Y328146D03*
X68800Y328316D03*
X75000Y403016D03*
X66250Y418266D03*
X91925Y119112D03*
X92405Y131997D03*
X81500Y167416D03*
X83500Y269516D03*
X87500D03*
X79500D03*
X92500Y403016D03*
X88500D03*
X84500D03*
X108500Y39016D03*
X106800Y85016D03*
X101500Y258016D03*
X97300Y257816D03*
X100500Y403016D03*
X104500D03*
X108500D03*
X116500Y39016D03*
X120331Y240016D03*
X122500Y253716D03*
X121918Y328504D03*
X116500Y403116D03*
X119100Y396316D03*
X112500Y403016D03*
X126200Y79516D03*
X132900Y181216D03*
X138000Y208016D03*
X132398Y224708D03*
X128720Y224706D03*
X137918Y328504D03*
X125918D03*
X129300Y426016D03*
X145500Y140516D03*
X148387Y150231D03*
X148400Y164616D03*
X148370Y172266D03*
X142150Y184091D03*
X149500Y229516D03*
X145600Y235416D03*
X142300Y275716D03*
X141918Y328504D03*
X143945Y348664D03*
X147900Y348616D03*
X143000Y419516D03*
X145200Y429466D03*
X163673Y85746D03*
X159673D03*
X159120Y119136D03*
X156500Y132516D03*
X160032Y216735D03*
X153500Y229016D03*
X164801Y257477D03*
X160973Y249527D03*
X153918Y328504D03*
X165026Y343712D03*
X157600Y429516D03*
X161450D03*
X173097Y85746D03*
X169097D03*
X171900Y134916D03*
X177413Y249527D03*
X173992Y257477D03*
X169967D03*
X171276Y423712D03*
X181400Y429716D03*
X175100Y423416D03*
X183800Y120016D03*
X195983Y134885D03*
X188000Y134916D03*
X192000D03*
X183413Y250227D03*
X191538Y250352D03*
X187550Y259756D03*
X193750Y368266D03*
X210778Y108860D03*
X212757Y134885D03*
X208627D03*
X204063Y250302D03*
X211700Y429216D03*
X207300D03*
X215000Y41016D03*
X214785Y108858D03*
X221278Y134885D03*
X217262D03*
X225284D03*
X220600Y324816D03*
X222800Y376291D03*
X213500Y386016D03*
X226500Y403816D03*
X219600Y429216D03*
X215700D03*
X234600Y108016D03*
X229396Y134885D03*
X238500Y332016D03*
X242500Y340516D03*
X243700Y106116D03*
X254332Y114174D03*
X250212Y135803D03*
X246205D03*
X256128Y250195D03*
X250505Y250169D03*
X242940Y258482D03*
X269800Y102416D03*
X258339Y114174D03*
X271674Y145320D03*
X272037Y245468D03*
X269400Y281516D03*
X267000Y416916D03*
X271900Y423816D03*
X257900Y423716D03*
X261900D03*
X277000Y44516D03*
X281300Y108416D03*
X285295Y120397D03*
X281250Y116016D03*
X277200D03*
X275684Y145320D03*
X279582Y245668D03*
X273250Y272516D03*
X284475Y372024D03*
X290000Y62516D03*
X301936Y146388D03*
X292000Y291016D03*
X299000Y291516D03*
X316066Y102834D03*
X316700Y119916D03*
X309936Y146388D03*
X313936D03*
X305936D03*
X311000Y323516D03*
X329825Y275913D03*
X330900Y317416D03*
X337223Y230573D03*
X337600Y275916D03*
G54D28*
X26613Y191653D03*
X28975D03*
Y201889D03*
G54D64*
X72410Y141603D03*
X79890D03*
X72410Y149088D03*
X79890D03*
X144260Y209000D03*
X151740D03*
X318134Y300232D03*
Y307682D03*
X327760Y118500D03*
X325614Y300232D03*
Y307682D03*
X335240Y118500D03*
G54D82*
X126378Y105000D03*
Y122500D03*
G54D55*
X59441Y141011D03*
Y148589D03*
X62000D03*
X57141Y197411D03*
X62259D03*
X57141Y204989D03*
X59700D03*
X62259D03*
X64559Y141011D03*
Y148589D03*
X160559Y273711D03*
X158000D03*
X155441D03*
X160559Y281289D03*
X155441D03*
G54D73*
X121882Y61037D03*
G54D91*
X166719Y73224D03*
G54D46*
X47059Y64760D03*
X44500D03*
X41941D03*
Y72240D03*
X44500D03*
X47059D03*
G54D37*
X30705Y252508D03*
G54D38*
X26768Y251327D03*
G54D92*
X166719Y70222D03*
G54D56*
X63300Y241363D03*
X60741D03*
Y249237D03*
X63300D03*
X65859Y241363D03*
Y249237D03*
X90059Y241363D03*
X87500D03*
X84941D03*
Y249237D03*
X87500D03*
X90059D03*
G54D65*
X71369Y163879D03*
X68810D03*
X66251D03*
Y172541D03*
X71369D03*
G54D74*
X113760Y74441D03*
Y77000D03*
X121240D03*
Y74441D03*
X113760Y79559D03*
X121240D03*
X132740Y44459D03*
Y41900D03*
Y39341D03*
X125260D03*
Y41900D03*
Y44459D03*
X253240Y46559D03*
Y44000D03*
Y41441D03*
X245760D03*
Y44000D03*
Y46559D03*
G54D83*
X137240Y152985D03*
X133500D03*
X129760D03*
X137240Y163615D03*
X133500D03*
X129760D03*
G54D29*
X33109Y190078D03*
G54D47*
X45276Y89000D03*
Y109000D03*
X56102Y99000D03*
X197587Y338200D03*
X208413Y328200D03*
Y348200D03*
X254087Y69500D03*
X264913Y59500D03*
Y79500D03*
G54D48*
X47760Y226076D03*
Y235524D03*
X55240Y226076D03*
X51500D03*
X55240Y235524D03*
X297760Y320382D03*
Y330618D03*
X301500D03*
X305240Y320382D03*
Y330618D03*
G54D66*
X77384Y240085D03*
X75416D03*
X73447D03*
X77384Y250715D03*
X75416D03*
X73447D03*
X79353Y240085D03*
Y250715D03*
X101253Y239985D03*
X99284D03*
X97316D03*
X95347D03*
X101253Y250615D03*
X99284D03*
X97316D03*
X95347D03*
G54D84*
X138261Y216285D03*
Y224159D03*
Y218253D03*
Y220222D03*
Y222191D03*
X150467Y224159D03*
Y216285D03*
Y222191D03*
Y220222D03*
Y218253D03*
G54D75*
X121095Y68911D03*
X128575Y61037D03*
Y68911D03*
G54D93*
X162782Y73126D03*
X164751D03*
Y70074D03*
X162782D03*
X168687Y73126D03*
X170656D03*
Y70074D03*
X168687D03*
G54D39*
X28255Y272190D03*
Y295220D03*
X83341Y87348D03*
Y110378D03*
X324605Y245210D03*
Y268240D03*
G54D57*
X64567Y315493D03*
X146063D03*
G54D49*
X36414Y256051D03*
G54D85*
X138013Y365197D03*
Y405749D03*
X153013Y365197D03*
X148013D03*
X143013D03*
Y405749D03*
X148013D03*
X153013D03*
X168013Y365197D03*
X163013D03*
X158013D03*
Y405749D03*
X163013D03*
X168013D03*
X173013Y365197D03*
Y405749D03*
G54D76*
X120300Y85451D03*
X116560D03*
X112820D03*
Y94900D03*
X116560D03*
X120300D03*
G54D67*
X69750Y271100D03*
Y276900D03*
X80500Y161400D03*
Y155600D03*
X326000Y314100D03*
Y319900D03*
G54D94*
X163334Y90590D03*
Y83898D03*
X159988D03*
Y90590D03*
X172758D03*
Y83898D03*
X169412D03*
Y90590D03*
G54D58*
X60864Y344831D03*
Y360579D03*
Y357429D03*
Y354280D03*
Y351130D03*
Y347981D03*
Y376327D03*
Y373177D03*
Y370028D03*
Y366878D03*
Y363729D03*
Y388925D03*
Y385776D03*
Y382626D03*
Y379477D03*
Y392075D03*
X64014Y344831D03*
X67163D03*
X70313D03*
X73462D03*
X76612D03*
X64014Y360579D03*
X67163D03*
X70313D03*
X73462D03*
X76612D03*
X64014Y357429D03*
X67163D03*
X70313D03*
X73462D03*
X76612D03*
X64014Y354280D03*
X67163D03*
X70313D03*
X73462D03*
X76612D03*
X64014Y351130D03*
X67163D03*
X70313D03*
X73462D03*
X76612D03*
X64014Y347981D03*
X67163D03*
X70313D03*
X73462D03*
X76612D03*
X64014Y376327D03*
X67163D03*
X70313D03*
X73462D03*
X76612D03*
X64014Y373177D03*
X67163D03*
X70313D03*
X73462D03*
X76612D03*
X64014Y370028D03*
X67163D03*
X70313D03*
X73462D03*
X76612D03*
X64014Y366878D03*
X67163D03*
X70313D03*
X73462D03*
X76612D03*
X64014Y363729D03*
X67163D03*
X70313D03*
X73462D03*
X76612D03*
X64014Y388925D03*
X67163D03*
X70313D03*
X73462D03*
X76612D03*
X64014Y385776D03*
X67163D03*
X70313D03*
X73462D03*
X76612D03*
X64014Y382626D03*
X67163D03*
X70313D03*
X73462D03*
X76612D03*
X64014Y379477D03*
X67163D03*
X70313D03*
X73462D03*
X76612D03*
X64014Y392075D03*
X67163D03*
X70313D03*
X73462D03*
X76612D03*
X79762Y344831D03*
X82911D03*
X86061D03*
X89210D03*
X92360D03*
X79762Y360579D03*
X82911D03*
X86061D03*
X89210D03*
X92360D03*
X79762Y357429D03*
X82911D03*
X86061D03*
X89210D03*
X92360D03*
X79762Y354280D03*
X82911D03*
X86061D03*
X89210D03*
X92360D03*
X79762Y351130D03*
X82911D03*
X86061D03*
X89210D03*
X92360D03*
X79762Y347981D03*
X82911D03*
X86061D03*
X89210D03*
X92360D03*
X79762Y376327D03*
X82911D03*
X86061D03*
X89210D03*
X92360D03*
X79762Y373177D03*
X82911D03*
X86061D03*
X89210D03*
X92360D03*
X79762Y370028D03*
X82911D03*
X86061D03*
X89210D03*
X92360D03*
X79762Y366878D03*
X82911D03*
X86061D03*
X89210D03*
X92360D03*
X79762Y363729D03*
X82911D03*
X86061D03*
X89210D03*
X92360D03*
X79762Y388925D03*
X82911D03*
X86061D03*
X89210D03*
X92360D03*
X79762Y385776D03*
X82911D03*
X86061D03*
X89210D03*
X92360D03*
X79762Y382626D03*
X82911D03*
X86061D03*
X89210D03*
X92360D03*
X79762Y379477D03*
X82911D03*
X86061D03*
X89210D03*
X92360D03*
X79762Y392075D03*
X82911D03*
X86061D03*
X89210D03*
X92360D03*
X95510Y344831D03*
X98659D03*
X101809D03*
X104958D03*
X108108D03*
X95510Y360579D03*
X98659D03*
X101809D03*
X104958D03*
X108108D03*
X95510Y357429D03*
X98659D03*
X101809D03*
X104958D03*
X108108D03*
X95510Y354280D03*
X98659D03*
X101809D03*
X104958D03*
X108108D03*
X95510Y351130D03*
X98659D03*
X101809D03*
X104958D03*
X108108D03*
X95510Y347981D03*
X98659D03*
X101809D03*
X104958D03*
X108108D03*
X95510Y376327D03*
X98659D03*
X101809D03*
X104958D03*
X108108D03*
X95510Y373177D03*
X98659D03*
X101809D03*
X104958D03*
X108108D03*
X95510Y370028D03*
X98659D03*
X101809D03*
X104958D03*
X108108D03*
X95510Y366878D03*
X98659D03*
X101809D03*
X104958D03*
X108108D03*
X95510Y363729D03*
X98659D03*
X101809D03*
X104958D03*
X108108D03*
X95510Y388925D03*
X98659D03*
X101809D03*
X104958D03*
X108108D03*
X95510Y385776D03*
X98659D03*
X101809D03*
X104958D03*
X108108D03*
X95510Y382626D03*
X98659D03*
X101809D03*
X104958D03*
X108108D03*
X95510Y379477D03*
X98659D03*
X101809D03*
X104958D03*
X108108D03*
X95510Y392075D03*
X98659D03*
X101809D03*
X104958D03*
X108108D03*
X176752Y167603D03*
X179902D03*
X176752Y164454D03*
X179902D03*
X176752Y161304D03*
X179902D03*
X176752Y158155D03*
X179902D03*
X176752Y155005D03*
X179902D03*
X176752Y180202D03*
X179902D03*
X176752Y177052D03*
X179902D03*
X176752Y173903D03*
X179902D03*
X176752Y170753D03*
X179902D03*
X176752Y195950D03*
X179902D03*
X176752Y192800D03*
X179902D03*
X176752Y189651D03*
X179902D03*
X176752Y186501D03*
X179902D03*
X176752Y183351D03*
X179902D03*
X176752Y211698D03*
X179902D03*
X176752Y208548D03*
X179902D03*
X176752Y205399D03*
X179902D03*
X176752Y202249D03*
X179902D03*
X176752Y199099D03*
X179902D03*
X176752Y227446D03*
X179902D03*
X176752Y224296D03*
X179902D03*
X176752Y221147D03*
X179902D03*
X176752Y217997D03*
X179902D03*
X176752Y214847D03*
X179902D03*
X176752Y233745D03*
X179902D03*
X176752Y230595D03*
X179902D03*
X183051Y167603D03*
X186201D03*
X189350D03*
X192500D03*
X195650D03*
X183051Y164454D03*
X186201D03*
X189350D03*
X192500D03*
X195650D03*
X183051Y161304D03*
X186201D03*
X189350D03*
X192500D03*
X195650D03*
X183051Y158155D03*
X186201D03*
X189350D03*
X192500D03*
X195650D03*
X183051Y155005D03*
X186201D03*
X189350D03*
X192500D03*
X195650D03*
X183051Y180202D03*
X186201D03*
X189350D03*
X192500D03*
X183051Y177052D03*
X186201D03*
X189350D03*
X192500D03*
X183051Y173903D03*
X186201D03*
X189350D03*
X192500D03*
X183051Y170753D03*
X186201D03*
X189350D03*
X192500D03*
X195650D03*
X183051Y195950D03*
X186201D03*
X189350D03*
X192500D03*
X183051Y192800D03*
X186201D03*
X189350D03*
X192500D03*
X183051Y189651D03*
X186201D03*
X189350D03*
X192500D03*
X183051Y186501D03*
X186201D03*
X189350D03*
X192500D03*
X183051Y183351D03*
X186201D03*
X189350D03*
X192500D03*
X183051Y211698D03*
X186201D03*
X189350D03*
X192500D03*
X183051Y208548D03*
X186201D03*
X189350D03*
X192500D03*
X183051Y205399D03*
X186201D03*
X189350D03*
X192500D03*
X183051Y202249D03*
X186201D03*
X189350D03*
X192500D03*
X183051Y199099D03*
X186201D03*
X189350D03*
X192500D03*
X183051Y227446D03*
X186201D03*
X189350D03*
X192500D03*
X195650D03*
X183051Y224296D03*
X186201D03*
X189350D03*
X192500D03*
X195650D03*
X183051Y221147D03*
X186201D03*
X189350D03*
X192500D03*
X195650D03*
X183051Y217997D03*
X186201D03*
X189350D03*
X192500D03*
X195650D03*
X183051Y214847D03*
X186201D03*
X189350D03*
X192500D03*
X183051Y233745D03*
X186201D03*
X189350D03*
X192500D03*
X195650D03*
X183051Y230595D03*
X186201D03*
X189350D03*
X192500D03*
X195650D03*
X198799Y167603D03*
X201949D03*
X205098D03*
X208248D03*
X211398D03*
X198799Y164454D03*
X201949D03*
X205098D03*
X208248D03*
X211398D03*
X198799Y161304D03*
X201949D03*
X205098D03*
X208248D03*
X211398D03*
X198799Y158155D03*
X201949D03*
X205098D03*
X208248D03*
X211398D03*
X198799Y155005D03*
X201949D03*
X205098D03*
X208248D03*
X211398D03*
X198799Y180202D03*
X201949D03*
X205098D03*
X208248D03*
X211398D03*
X198799Y177052D03*
X201949D03*
X205098D03*
X208248D03*
X211398D03*
X198799Y170753D03*
X201949D03*
X205098D03*
X208248D03*
X211398D03*
X198799Y195950D03*
X201949D03*
X205098D03*
X208248D03*
X211398D03*
X198799Y192800D03*
X201949D03*
X205098D03*
X208248D03*
X211398D03*
X198799Y189651D03*
X201949D03*
X205098D03*
X208248D03*
X211398D03*
X198799Y186501D03*
X201949D03*
X205098D03*
X208248D03*
X211398D03*
X198799Y183351D03*
X201949D03*
X205098D03*
X208248D03*
X211398D03*
X198799Y211698D03*
X201949D03*
X205098D03*
X208248D03*
X211398D03*
X198799Y208548D03*
X201949D03*
X205098D03*
X208248D03*
X211398D03*
X198799Y205399D03*
X201949D03*
X205098D03*
X208248D03*
X211398D03*
X198799Y202249D03*
X201949D03*
X205098D03*
X208248D03*
X211398D03*
X198799Y199099D03*
X201949D03*
X205098D03*
X208248D03*
X211398D03*
X198799Y227446D03*
X201949D03*
X205098D03*
X208248D03*
X211398D03*
X198799Y224296D03*
X201949D03*
X205098D03*
X208248D03*
X211398D03*
X198799Y221147D03*
X201949D03*
X205098D03*
X208248D03*
X211398D03*
X198799Y217997D03*
X201949D03*
X205098D03*
X208248D03*
X211398D03*
X198799Y233745D03*
X201949D03*
X205098D03*
X208248D03*
X211398D03*
X198799Y230595D03*
X201949D03*
X205098D03*
X208248D03*
X211398D03*
X214547Y167603D03*
X217697D03*
X220846D03*
X223996D03*
X227146D03*
X214547Y164454D03*
X217697D03*
X220846D03*
X223996D03*
X227146D03*
X214547Y161304D03*
X217697D03*
X220846D03*
X223996D03*
X227146D03*
X214547Y158155D03*
X217697D03*
X220846D03*
X223996D03*
X227146D03*
X214547Y155005D03*
X217697D03*
X220846D03*
X223996D03*
X227146D03*
X214547Y180202D03*
X217697D03*
X220846D03*
X223996D03*
X227146D03*
X214547Y177052D03*
X217697D03*
X220846D03*
X223996D03*
X227146D03*
X214547Y170753D03*
X217697D03*
X220846D03*
X223996D03*
X227146D03*
X214547Y195950D03*
X217697D03*
X220846D03*
X223996D03*
X227146D03*
X214547Y192800D03*
X217697D03*
X220846D03*
X223996D03*
X227146D03*
X214547Y189651D03*
X217697D03*
X220846D03*
X223996D03*
X227146D03*
X214547Y186501D03*
X217697D03*
X220846D03*
X223996D03*
X227146D03*
X214547Y183351D03*
X217697D03*
X220846D03*
X223996D03*
X227146D03*
X214547Y211698D03*
X217697D03*
X220846D03*
X223996D03*
X227146D03*
X214547Y208548D03*
X217697D03*
X220846D03*
X223996D03*
X227146D03*
X214547Y205399D03*
X217697D03*
X220846D03*
X223996D03*
X227146D03*
X214547Y202249D03*
X217697D03*
X220846D03*
X223996D03*
X227146D03*
X214547Y199099D03*
X217697D03*
X220846D03*
X223996D03*
X227146D03*
X214547Y227446D03*
X217697D03*
X220846D03*
X223996D03*
X227146D03*
X214547Y224296D03*
X217697D03*
X220846D03*
X223996D03*
X227146D03*
X214547Y221147D03*
X217697D03*
X220846D03*
X223996D03*
X227146D03*
X214547Y217997D03*
X217697D03*
X220846D03*
X223996D03*
X227146D03*
X214547Y233745D03*
X217697D03*
X220846D03*
X223996D03*
X227146D03*
X214547Y230595D03*
X217697D03*
X220846D03*
X223996D03*
X227146D03*
X230295Y167603D03*
X233445D03*
X236594D03*
X239744D03*
X230295Y164454D03*
X233445D03*
X236594D03*
X239744D03*
X230295Y161304D03*
X233445D03*
X236594D03*
X239744D03*
X230295Y158155D03*
X233445D03*
X236594D03*
X239744D03*
X230295Y155005D03*
X233445D03*
X236594D03*
X239744D03*
X230295Y180202D03*
X233445D03*
X239744D03*
X230295Y177052D03*
X233445D03*
X239744D03*
Y173903D03*
X230295Y170753D03*
X233445D03*
X236594D03*
X239744D03*
X230295Y195950D03*
X233445D03*
X239744D03*
X230295Y192800D03*
X233445D03*
X239744D03*
X230295Y189651D03*
X233445D03*
X239744D03*
X230295Y186501D03*
X233445D03*
X239744D03*
X230295Y183351D03*
X233445D03*
X239744D03*
X230295Y211698D03*
X233445D03*
X239744D03*
X230295Y208548D03*
X233445D03*
X239744D03*
X230295Y205399D03*
X233445D03*
X239744D03*
X230295Y202249D03*
X233445D03*
X239744D03*
X230295Y199099D03*
X233445D03*
X239744D03*
X230295Y227446D03*
X233445D03*
X236594D03*
X239744D03*
X230295Y224296D03*
X233445D03*
X236594D03*
X239744D03*
X230295Y221147D03*
X233445D03*
X236594D03*
X239744D03*
X230295Y217997D03*
X233445D03*
X236594D03*
X239744D03*
Y214847D03*
X230295Y233745D03*
X233445D03*
X236594D03*
X239744D03*
X230295Y230595D03*
X233445D03*
X236594D03*
X239744D03*
X242894Y167603D03*
X246043D03*
X249193D03*
X252342D03*
X255492D03*
X242894Y164454D03*
X246043D03*
X249193D03*
X252342D03*
X255492D03*
X242894Y161304D03*
X246043D03*
X249193D03*
X252342D03*
X255492D03*
X242894Y158155D03*
X246043D03*
X249193D03*
X252342D03*
X255492D03*
X242894Y155005D03*
X246043D03*
X249193D03*
X252342D03*
X255492D03*
X242894Y180202D03*
X246043D03*
X249193D03*
X252342D03*
X255492D03*
X242894Y177052D03*
X246043D03*
X249193D03*
X252342D03*
X255492D03*
X242894Y173903D03*
X246043D03*
X249193D03*
X252342D03*
X255492D03*
X242894Y170753D03*
X246043D03*
X249193D03*
X252342D03*
X255492D03*
X242894Y195950D03*
X246043D03*
X249193D03*
X252342D03*
X255492D03*
X242894Y192800D03*
X246043D03*
X249193D03*
X252342D03*
X255492D03*
X242894Y189651D03*
X246043D03*
X249193D03*
X252342D03*
X255492D03*
X242894Y186501D03*
X246043D03*
X249193D03*
X252342D03*
X255492D03*
X242894Y183351D03*
X246043D03*
X249193D03*
X252342D03*
X255492D03*
X242894Y211698D03*
X246043D03*
X249193D03*
X252342D03*
X255492D03*
X242894Y208548D03*
X246043D03*
X249193D03*
X252342D03*
X255492D03*
X242894Y205399D03*
X246043D03*
X249193D03*
X252342D03*
X255492D03*
X242894Y202249D03*
X246043D03*
X249193D03*
X252342D03*
X255492D03*
X242894Y199099D03*
X246043D03*
X249193D03*
X252342D03*
X255492D03*
X242894Y227446D03*
X246043D03*
X249193D03*
X252342D03*
X255492D03*
X242894Y224296D03*
X246043D03*
X249193D03*
X252342D03*
X255492D03*
X242894Y221147D03*
X246043D03*
X249193D03*
X252342D03*
X255492D03*
X242894Y217997D03*
X246043D03*
X249193D03*
X252342D03*
X255492D03*
X242894Y214847D03*
X246043D03*
X249193D03*
X252342D03*
X255492D03*
X242894Y233745D03*
X246043D03*
X249193D03*
X252342D03*
X255492D03*
X242894Y230595D03*
X246043D03*
X249193D03*
X252342D03*
X255492D03*
G54D86*
X138012Y366574D03*
Y404370D03*
X153012Y366574D03*
X148012D03*
X143012D03*
Y404370D03*
X148012D03*
X153012D03*
X168012Y366574D03*
X163012D03*
X158012D03*
Y404370D03*
X163012D03*
X168012D03*
X173012Y366574D03*
Y404370D03*
G54D95*
X161877Y107140D03*
Y103400D03*
Y99660D03*
X171523D03*
Y107140D03*
G54D77*
X123376Y105000D03*
Y122500D03*
G54D68*
X73819Y288821D03*
X71850D03*
X69882D03*
X74803Y318544D03*
X72835D03*
X70866D03*
X68898D03*
X91535Y288821D03*
X89567D03*
X87598D03*
X85630D03*
X83661D03*
X92520Y318544D03*
X90551D03*
X88583D03*
X86614D03*
X84646D03*
X107283Y288821D03*
X105315D03*
X103347D03*
X101378D03*
X99409D03*
X97441D03*
X95472D03*
X93504D03*
X106299Y318544D03*
X104331D03*
X102362D03*
X100394D03*
X98425D03*
X96457D03*
X94488D03*
X123032Y288821D03*
X121063D03*
X119095D03*
X117126D03*
X115158D03*
X113189D03*
X111221D03*
X109252D03*
X122047Y318544D03*
X120079D03*
X118110D03*
X116142D03*
X114173D03*
X112205D03*
X110236D03*
X108268D03*
X136811Y288821D03*
X134843D03*
X132874D03*
X130906D03*
X128937D03*
X126969D03*
X125000D03*
X137795Y318544D03*
X135827D03*
X133858D03*
X131890D03*
X129921D03*
X127953D03*
X125984D03*
X124016D03*
X140748Y288821D03*
X138780D03*
X141732Y318544D03*
X139764D03*
G54D59*
X59303Y421214D03*
Y416096D03*
X51823D03*
Y418655D03*
Y421214D03*
G54D69*
X74419Y417300D03*
X83081Y421040D03*
Y413560D03*
G54D78*
X123474Y101063D03*
Y103032D03*
Y106968D03*
Y118563D03*
Y120532D03*
Y108937D03*
Y124468D03*
Y126437D03*
X126526Y106968D03*
Y103032D03*
Y101063D03*
Y120532D03*
Y118563D03*
Y108937D03*
Y126437D03*
Y124468D03*
G54D96*
X176953Y266800D03*
X171047D03*
X297821Y108055D03*
X291380Y106255D03*
X297821Y122106D03*
X291380Y120306D03*
X297821Y113961D03*
X291380Y112161D03*
X297821Y128012D03*
X291380Y126212D03*
X310661Y108055D03*
X304259Y106255D03*
Y120306D03*
X310661Y122106D03*
Y113961D03*
X304259Y112161D03*
Y126212D03*
X310661Y128012D03*
G54D87*
X153237Y58583D03*
X165048Y52677D03*
X161111Y58583D03*
X168985D03*
X182764Y52677D03*
X172922D03*
X176859Y58583D03*
X184733D03*
G54D88*
X146260Y72126D03*
Y129606D03*
G54D97*
X197200Y71000D03*
Y80000D03*
X208800Y71000D03*
Y80000D03*
G54D79*
X115359Y242060D03*
X112800D03*
X110241D03*
Y249540D03*
X112800D03*
X115359D03*
G54D98*
X197111Y88586D03*
Y92326D03*
Y96066D03*
X205969Y92326D03*
Y88586D03*
Y96066D03*
G54D89*
X144364Y220222D03*
G54D99*
X197012Y296565D03*
Y304635D03*
X210988Y296565D03*
Y304635D03*
M02*
